FILE_TYPE = MACRO_DRAWING;
SET COLOR_WIRE YELLOW;
SET COLOR_PROP ORANGE;
SET COLOR_DOT WHITE;
SET COLOR_ARC YELLOW;
SET COLOR_BODY GREEN;
SET COLOR_NOTE PURPLE;
SET PROP_DISPLAY VALUE;
SET PAGE_NUMBER P96;
FORCEADD OFFPAGE..5
(-8325 1625);
FORCEPROP 2 LAST $XR0 21 
J 0
(-8549 1625);
DISPLAY 0.638298 (-8549 1625);
PAINT MONO (-8549 1625);
FORCEPROP 2 LAST CDS_LIB mstr_standard
J 0
(-8325 1625);
DISPLAY 0.808511 (-8325 1625);
DISPLAY INVISIBLE (-8325 1625);
FORCEPROP 1 LAST OFFPAGE TRUE
J 0
(-8000 1500);
DISPLAY 0.872340 (-8000 1500);
PAINT GREEN (-8000 1500);
DISPLAY INVISIBLE (-8000 1500);
FORCEPROP 1 LAST COMMENT_BODY TRUE
J 0
(-8225 1550);
DISPLAY 0.872340 (-8225 1550);
PAINT GREEN (-8225 1550);
DISPLAY INVISIBLE (-8225 1550);
FORCEPROP 2 LAST PATH I1
J 0
(-8275 1700);
DISPLAY 1.021277 (-8275 1700);
DISPLAY INVISIBLE (-8275 1700);
FORCEADD OFFPAGE..6
(-8325 3275);
FORCEPROP 2 LAST $XR0 21 
J 0
(-8574 3275);
DISPLAY 0.638298 (-8574 3275);
PAINT MONO (-8574 3275);
FORCEPROP 2 LAST CDS_LIB mstr_standard
J 0
(-8325 3275);
DISPLAY 0.723404 (-8325 3275);
PAINT MONO (-8325 3275);
DISPLAY INVISIBLE (-8325 3275);
FORCEPROP 1 LAST OFFPAGE TRUE
J 0
(-8000 3150);
DISPLAY 0.872340 (-8000 3150);
PAINT GREEN (-8000 3150);
DISPLAY INVISIBLE (-8000 3150);
FORCEPROP 1 LAST COMMENT_BODY TRUE
J 0
(-8225 3200);
DISPLAY 0.872340 (-8225 3200);
PAINT GREEN (-8225 3200);
DISPLAY INVISIBLE (-8225 3200);
FORCEPROP 2 LAST PATH I10
J 0
(-8275 3350);
DISPLAY 1.021277 (-8275 3350);
DISPLAY INVISIBLE (-8275 3350);
FORCEADD TAP..1
(-6025 3925);
FORCEPROP 3 LASTPIN (-6075 3925) SIG_NAME M_L_CPU0_SA_DQ<8>
J 0
(-6065 3935);
DISPLAY 0.659574 (-6065 3935);
PAINT MONO (-6065 3935);
DISPLAY INVISIBLE (-6065 3935);
FORCEPROP 1 LASTPIN (-6075 3925) BN 8
J 0
(-6087 3933);
DISPLAY 0.489362 (-6087 3933);
PAINT GREEN (-6087 3933);
FORCEPROP 2 LAST CDS_LIB mstr_standard
J 0
(-6025 3925);
DISPLAY 0.723404 (-6025 3925);
PAINT MONO (-6025 3925);
DISPLAY INVISIBLE (-6025 3925);
FORCEPROP 1 LAST BODY_TYPE PLUMBING
J 0
(-6025 3975);
DISPLAY 0.872340 (-6025 3975);
PAINT GREEN (-6025 3975);
DISPLAY INVISIBLE (-6025 3975);
FORCEPROP 1 LAST HDL_TAP TRUE
J 0
(-5700 3800);
DISPLAY 0.872340 (-5700 3800);
DISPLAY INVISIBLE (-5700 3800);
FORCEPROP 1 LAST PATH I100
J 0
(-6027 3925);
DISPLAY 0.872340 (-6027 3925);
PAINT GREEN (-6027 3925);
DISPLAY INVISIBLE (-6027 3925);
FORCEADD TAP..1
(-6025 3975);
FORCEPROP 3 LASTPIN (-6075 3975) SIG_NAME M_L_CPU0_SA_DQ<9>
J 0
(-6065 3985);
DISPLAY 0.659574 (-6065 3985);
PAINT MONO (-6065 3985);
DISPLAY INVISIBLE (-6065 3985);
FORCEPROP 1 LASTPIN (-6075 3975) BN 9
J 0
(-6087 3983);
DISPLAY 0.489362 (-6087 3983);
PAINT GREEN (-6087 3983);
FORCEPROP 2 LAST CDS_LIB mstr_standard
J 0
(-6025 3975);
DISPLAY 0.723404 (-6025 3975);
PAINT MONO (-6025 3975);
DISPLAY INVISIBLE (-6025 3975);
FORCEPROP 1 LAST BODY_TYPE PLUMBING
J 0
(-6025 4025);
DISPLAY 0.872340 (-6025 4025);
PAINT GREEN (-6025 4025);
DISPLAY INVISIBLE (-6025 4025);
FORCEPROP 1 LAST HDL_TAP TRUE
J 0
(-5700 3850);
DISPLAY 0.872340 (-5700 3850);
DISPLAY INVISIBLE (-5700 3850);
FORCEPROP 1 LAST PATH I101
J 0
(-6027 3975);
DISPLAY 0.872340 (-6027 3975);
PAINT GREEN (-6027 3975);
DISPLAY INVISIBLE (-6027 3975);
FORCEADD TAP..1
(-6025 4025);
FORCEPROP 3 LASTPIN (-6075 4025) SIG_NAME M_L_CPU0_SA_DQ<10>
J 0
(-6065 4035);
DISPLAY 0.659574 (-6065 4035);
PAINT MONO (-6065 4035);
DISPLAY INVISIBLE (-6065 4035);
FORCEPROP 1 LASTPIN (-6075 4025) BN 10
J 0
(-6087 4033);
DISPLAY 0.489362 (-6087 4033);
PAINT GREEN (-6087 4033);
FORCEPROP 2 LAST CDS_LIB mstr_standard
J 0
(-6025 4025);
DISPLAY 0.723404 (-6025 4025);
PAINT MONO (-6025 4025);
DISPLAY INVISIBLE (-6025 4025);
FORCEPROP 1 LAST BODY_TYPE PLUMBING
J 0
(-6025 4075);
DISPLAY 0.872340 (-6025 4075);
PAINT GREEN (-6025 4075);
DISPLAY INVISIBLE (-6025 4075);
FORCEPROP 1 LAST HDL_TAP TRUE
J 0
(-5700 3900);
DISPLAY 0.872340 (-5700 3900);
DISPLAY INVISIBLE (-5700 3900);
FORCEPROP 1 LAST PATH I102
J 0
(-6027 4025);
DISPLAY 0.872340 (-6027 4025);
PAINT GREEN (-6027 4025);
DISPLAY INVISIBLE (-6027 4025);
FORCEADD TAP..1
(-6025 4125);
FORCEPROP 3 LASTPIN (-6075 4125) SIG_NAME M_L_CPU0_SA_DQ<12>
J 0
(-6065 4135);
DISPLAY 0.659574 (-6065 4135);
PAINT MONO (-6065 4135);
DISPLAY INVISIBLE (-6065 4135);
FORCEPROP 1 LASTPIN (-6075 4125) BN 12
J 0
(-6087 4133);
DISPLAY 0.489362 (-6087 4133);
PAINT GREEN (-6087 4133);
FORCEPROP 2 LAST CDS_LIB mstr_standard
J 0
(-6025 4125);
DISPLAY 0.723404 (-6025 4125);
PAINT MONO (-6025 4125);
DISPLAY INVISIBLE (-6025 4125);
FORCEPROP 1 LAST BODY_TYPE PLUMBING
J 0
(-6025 4175);
DISPLAY 0.872340 (-6025 4175);
PAINT GREEN (-6025 4175);
DISPLAY INVISIBLE (-6025 4175);
FORCEPROP 1 LAST HDL_TAP TRUE
J 0
(-5700 4000);
DISPLAY 0.872340 (-5700 4000);
DISPLAY INVISIBLE (-5700 4000);
FORCEPROP 1 LAST PATH I103
J 0
(-6027 4125);
DISPLAY 0.872340 (-6027 4125);
PAINT GREEN (-6027 4125);
DISPLAY INVISIBLE (-6027 4125);
FORCEADD TAP..1
(-6025 4075);
FORCEPROP 3 LASTPIN (-6075 4075) SIG_NAME M_L_CPU0_SA_DQ<11>
J 0
(-6065 4085);
DISPLAY 0.659574 (-6065 4085);
PAINT MONO (-6065 4085);
DISPLAY INVISIBLE (-6065 4085);
FORCEPROP 1 LASTPIN (-6075 4075) BN 11
J 0
(-6087 4083);
DISPLAY 0.489362 (-6087 4083);
PAINT GREEN (-6087 4083);
FORCEPROP 2 LAST CDS_LIB mstr_standard
J 0
(-6025 4075);
DISPLAY 0.723404 (-6025 4075);
PAINT MONO (-6025 4075);
DISPLAY INVISIBLE (-6025 4075);
FORCEPROP 1 LAST BODY_TYPE PLUMBING
J 0
(-6025 4125);
DISPLAY 0.872340 (-6025 4125);
PAINT GREEN (-6025 4125);
DISPLAY INVISIBLE (-6025 4125);
FORCEPROP 1 LAST HDL_TAP TRUE
J 0
(-5700 3950);
DISPLAY 0.872340 (-5700 3950);
DISPLAY INVISIBLE (-5700 3950);
FORCEPROP 1 LAST PATH I104
J 0
(-6027 4075);
DISPLAY 0.872340 (-6027 4075);
PAINT GREEN (-6027 4075);
DISPLAY INVISIBLE (-6027 4075);
FORCEADD TAP..1
(-6025 4175);
FORCEPROP 3 LASTPIN (-6075 4175) SIG_NAME M_L_CPU0_SA_DQ<13>
J 0
(-6065 4185);
DISPLAY 0.659574 (-6065 4185);
PAINT MONO (-6065 4185);
DISPLAY INVISIBLE (-6065 4185);
FORCEPROP 1 LASTPIN (-6075 4175) BN 13
J 0
(-6087 4183);
DISPLAY 0.489362 (-6087 4183);
PAINT GREEN (-6087 4183);
FORCEPROP 2 LAST CDS_LIB mstr_standard
J 0
(-6025 4175);
DISPLAY 0.723404 (-6025 4175);
PAINT MONO (-6025 4175);
DISPLAY INVISIBLE (-6025 4175);
FORCEPROP 1 LAST BODY_TYPE PLUMBING
J 0
(-6025 4225);
DISPLAY 0.872340 (-6025 4225);
PAINT GREEN (-6025 4225);
DISPLAY INVISIBLE (-6025 4225);
FORCEPROP 1 LAST HDL_TAP TRUE
J 0
(-5700 4050);
DISPLAY 0.872340 (-5700 4050);
DISPLAY INVISIBLE (-5700 4050);
FORCEPROP 1 LAST PATH I105
J 0
(-6027 4175);
DISPLAY 0.872340 (-6027 4175);
PAINT GREEN (-6027 4175);
DISPLAY INVISIBLE (-6027 4175);
FORCEADD TAP..1
(-6025 4225);
FORCEPROP 3 LASTPIN (-6075 4225) SIG_NAME M_L_CPU0_SA_DQ<14>
J 0
(-6065 4235);
DISPLAY 0.659574 (-6065 4235);
PAINT MONO (-6065 4235);
DISPLAY INVISIBLE (-6065 4235);
FORCEPROP 1 LASTPIN (-6075 4225) BN 14
J 0
(-6087 4233);
DISPLAY 0.489362 (-6087 4233);
PAINT GREEN (-6087 4233);
FORCEPROP 2 LAST CDS_LIB mstr_standard
J 0
(-6025 4225);
DISPLAY 0.723404 (-6025 4225);
PAINT MONO (-6025 4225);
DISPLAY INVISIBLE (-6025 4225);
FORCEPROP 1 LAST BODY_TYPE PLUMBING
J 0
(-6025 4275);
DISPLAY 0.872340 (-6025 4275);
PAINT GREEN (-6025 4275);
DISPLAY INVISIBLE (-6025 4275);
FORCEPROP 1 LAST HDL_TAP TRUE
J 0
(-5700 4100);
DISPLAY 0.872340 (-5700 4100);
DISPLAY INVISIBLE (-5700 4100);
FORCEPROP 1 LAST PATH I106
J 0
(-6027 4225);
DISPLAY 0.872340 (-6027 4225);
PAINT GREEN (-6027 4225);
DISPLAY INVISIBLE (-6027 4225);
FORCEADD TAP..1
(-6025 4275);
FORCEPROP 3 LASTPIN (-6075 4275) SIG_NAME M_L_CPU0_SA_DQ<15>
J 0
(-6065 4285);
DISPLAY 0.659574 (-6065 4285);
PAINT MONO (-6065 4285);
DISPLAY INVISIBLE (-6065 4285);
FORCEPROP 1 LASTPIN (-6075 4275) BN 15
J 0
(-6087 4283);
DISPLAY 0.489362 (-6087 4283);
PAINT GREEN (-6087 4283);
FORCEPROP 2 LAST CDS_LIB mstr_standard
J 0
(-6025 4275);
DISPLAY 0.723404 (-6025 4275);
PAINT MONO (-6025 4275);
DISPLAY INVISIBLE (-6025 4275);
FORCEPROP 1 LAST BODY_TYPE PLUMBING
J 0
(-6025 4325);
DISPLAY 0.872340 (-6025 4325);
PAINT GREEN (-6025 4325);
DISPLAY INVISIBLE (-6025 4325);
FORCEPROP 1 LAST HDL_TAP TRUE
J 0
(-5700 4150);
DISPLAY 0.872340 (-5700 4150);
DISPLAY INVISIBLE (-5700 4150);
FORCEPROP 1 LAST PATH I107
J 0
(-6027 4275);
DISPLAY 0.872340 (-6027 4275);
PAINT GREEN (-6027 4275);
DISPLAY INVISIBLE (-6027 4275);
FORCEADD TAP..1
(-6025 4325);
FORCEPROP 3 LASTPIN (-6075 4325) SIG_NAME M_L_CPU0_SA_DQ<16>
J 0
(-6065 4335);
DISPLAY 0.659574 (-6065 4335);
PAINT MONO (-6065 4335);
DISPLAY INVISIBLE (-6065 4335);
FORCEPROP 1 LASTPIN (-6075 4325) BN 16
J 0
(-6087 4333);
DISPLAY 0.489362 (-6087 4333);
PAINT GREEN (-6087 4333);
FORCEPROP 2 LAST CDS_LIB mstr_standard
J 0
(-6025 4325);
DISPLAY 0.723404 (-6025 4325);
PAINT MONO (-6025 4325);
DISPLAY INVISIBLE (-6025 4325);
FORCEPROP 1 LAST BODY_TYPE PLUMBING
J 0
(-6025 4375);
DISPLAY 0.872340 (-6025 4375);
PAINT GREEN (-6025 4375);
DISPLAY INVISIBLE (-6025 4375);
FORCEPROP 1 LAST HDL_TAP TRUE
J 0
(-5700 4200);
DISPLAY 0.872340 (-5700 4200);
DISPLAY INVISIBLE (-5700 4200);
FORCEPROP 1 LAST PATH I108
J 0
(-6027 4325);
DISPLAY 0.872340 (-6027 4325);
PAINT GREEN (-6027 4325);
DISPLAY INVISIBLE (-6027 4325);
FORCEADD TAP..1
(-6025 4425);
FORCEPROP 3 LASTPIN (-6075 4425) SIG_NAME M_L_CPU0_SA_DQ<18>
J 0
(-6065 4435);
DISPLAY 0.659574 (-6065 4435);
PAINT MONO (-6065 4435);
DISPLAY INVISIBLE (-6065 4435);
FORCEPROP 1 LASTPIN (-6075 4425) BN 18
J 0
(-6087 4433);
DISPLAY 0.489362 (-6087 4433);
PAINT GREEN (-6087 4433);
FORCEPROP 2 LAST CDS_LIB mstr_standard
J 0
(-6025 4425);
DISPLAY 0.723404 (-6025 4425);
PAINT MONO (-6025 4425);
DISPLAY INVISIBLE (-6025 4425);
FORCEPROP 1 LAST BODY_TYPE PLUMBING
J 0
(-6025 4475);
DISPLAY 0.872340 (-6025 4475);
PAINT GREEN (-6025 4475);
DISPLAY INVISIBLE (-6025 4475);
FORCEPROP 1 LAST HDL_TAP TRUE
J 0
(-5700 4300);
DISPLAY 0.872340 (-5700 4300);
DISPLAY INVISIBLE (-5700 4300);
FORCEPROP 1 LAST PATH I109
J 0
(-6027 4425);
DISPLAY 0.872340 (-6027 4425);
PAINT GREEN (-6027 4425);
DISPLAY INVISIBLE (-6027 4425);
FORCEADD OFFPAGE..1
(-8325 3825);
FORCEPROP 2 LAST $XR0 21 
J 0
(-8546 3825);
DISPLAY 0.638298 (-8546 3825);
PAINT MONO (-8546 3825);
FORCEPROP 2 LAST CDS_LIB mstr_standard
J 0
(-8325 3825);
DISPLAY 0.723404 (-8325 3825);
PAINT MONO (-8325 3825);
DISPLAY INVISIBLE (-8325 3825);
FORCEPROP 1 LAST OFFPAGE TRUE
J 0
(-8000 3700);
DISPLAY 0.872340 (-8000 3700);
PAINT GREEN (-8000 3700);
DISPLAY INVISIBLE (-8000 3700);
FORCEPROP 1 LAST COMMENT_BODY TRUE
J 0
(-8200 3725);
DISPLAY 0.872340 (-8200 3725);
PAINT GREEN (-8200 3725);
DISPLAY INVISIBLE (-8200 3725);
FORCEPROP 2 LAST PATH I11
J 0
(-8275 3900);
DISPLAY 1.021277 (-8275 3900);
DISPLAY INVISIBLE (-8275 3900);
FORCEADD TAP..1
(-6025 4375);
FORCEPROP 3 LASTPIN (-6075 4375) SIG_NAME M_L_CPU0_SA_DQ<17>
J 0
(-6065 4385);
DISPLAY 0.659574 (-6065 4385);
PAINT MONO (-6065 4385);
DISPLAY INVISIBLE (-6065 4385);
FORCEPROP 1 LASTPIN (-6075 4375) BN 17
J 0
(-6087 4383);
DISPLAY 0.489362 (-6087 4383);
PAINT GREEN (-6087 4383);
FORCEPROP 2 LAST CDS_LIB mstr_standard
J 0
(-6025 4375);
DISPLAY 0.723404 (-6025 4375);
PAINT MONO (-6025 4375);
DISPLAY INVISIBLE (-6025 4375);
FORCEPROP 1 LAST BODY_TYPE PLUMBING
J 0
(-6025 4425);
DISPLAY 0.872340 (-6025 4425);
PAINT GREEN (-6025 4425);
DISPLAY INVISIBLE (-6025 4425);
FORCEPROP 1 LAST HDL_TAP TRUE
J 0
(-5700 4250);
DISPLAY 0.872340 (-5700 4250);
DISPLAY INVISIBLE (-5700 4250);
FORCEPROP 1 LAST PATH I110
J 0
(-6027 4375);
DISPLAY 0.872340 (-6027 4375);
PAINT GREEN (-6027 4375);
DISPLAY INVISIBLE (-6027 4375);
FORCEADD TAP..1
(-6025 4475);
FORCEPROP 3 LASTPIN (-6075 4475) SIG_NAME M_L_CPU0_SA_DQ<19>
J 0
(-6065 4485);
DISPLAY 0.659574 (-6065 4485);
PAINT MONO (-6065 4485);
DISPLAY INVISIBLE (-6065 4485);
FORCEPROP 1 LASTPIN (-6075 4475) BN 19
J 0
(-6087 4483);
DISPLAY 0.489362 (-6087 4483);
PAINT GREEN (-6087 4483);
FORCEPROP 2 LAST CDS_LIB mstr_standard
J 0
(-6025 4475);
DISPLAY 0.723404 (-6025 4475);
PAINT MONO (-6025 4475);
DISPLAY INVISIBLE (-6025 4475);
FORCEPROP 1 LAST BODY_TYPE PLUMBING
J 0
(-6025 4525);
DISPLAY 0.872340 (-6025 4525);
PAINT GREEN (-6025 4525);
DISPLAY INVISIBLE (-6025 4525);
FORCEPROP 1 LAST HDL_TAP TRUE
J 0
(-5700 4350);
DISPLAY 0.872340 (-5700 4350);
DISPLAY INVISIBLE (-5700 4350);
FORCEPROP 1 LAST PATH I111
J 0
(-6027 4475);
DISPLAY 0.872340 (-6027 4475);
PAINT GREEN (-6027 4475);
DISPLAY INVISIBLE (-6027 4475);
FORCEADD TAP..1
(-6025 4525);
FORCEPROP 3 LASTPIN (-6075 4525) SIG_NAME M_L_CPU0_SA_DQ<20>
J 0
(-6065 4535);
DISPLAY 0.659574 (-6065 4535);
PAINT MONO (-6065 4535);
DISPLAY INVISIBLE (-6065 4535);
FORCEPROP 1 LASTPIN (-6075 4525) BN 20
J 0
(-6087 4533);
DISPLAY 0.489362 (-6087 4533);
PAINT GREEN (-6087 4533);
FORCEPROP 2 LAST CDS_LIB mstr_standard
J 0
(-6025 4525);
DISPLAY 0.723404 (-6025 4525);
PAINT MONO (-6025 4525);
DISPLAY INVISIBLE (-6025 4525);
FORCEPROP 1 LAST BODY_TYPE PLUMBING
J 0
(-6025 4575);
DISPLAY 0.872340 (-6025 4575);
PAINT GREEN (-6025 4575);
DISPLAY INVISIBLE (-6025 4575);
FORCEPROP 1 LAST HDL_TAP TRUE
J 0
(-5700 4400);
DISPLAY 0.872340 (-5700 4400);
DISPLAY INVISIBLE (-5700 4400);
FORCEPROP 1 LAST PATH I112
J 0
(-6027 4525);
DISPLAY 0.872340 (-6027 4525);
PAINT GREEN (-6027 4525);
DISPLAY INVISIBLE (-6027 4525);
FORCEADD TAP..1
(-6025 4575);
FORCEPROP 3 LASTPIN (-6075 4575) SIG_NAME M_L_CPU0_SA_DQ<21>
J 0
(-6065 4585);
DISPLAY 0.659574 (-6065 4585);
PAINT MONO (-6065 4585);
DISPLAY INVISIBLE (-6065 4585);
FORCEPROP 1 LASTPIN (-6075 4575) BN 21
J 0
(-6087 4583);
DISPLAY 0.489362 (-6087 4583);
PAINT GREEN (-6087 4583);
FORCEPROP 2 LAST CDS_LIB mstr_standard
J 0
(-6025 4575);
DISPLAY 0.723404 (-6025 4575);
PAINT MONO (-6025 4575);
DISPLAY INVISIBLE (-6025 4575);
FORCEPROP 1 LAST BODY_TYPE PLUMBING
J 0
(-6025 4625);
DISPLAY 0.872340 (-6025 4625);
PAINT GREEN (-6025 4625);
DISPLAY INVISIBLE (-6025 4625);
FORCEPROP 1 LAST HDL_TAP TRUE
J 0
(-5700 4450);
DISPLAY 0.872340 (-5700 4450);
DISPLAY INVISIBLE (-5700 4450);
FORCEPROP 1 LAST PATH I113
J 0
(-6027 4575);
DISPLAY 0.872340 (-6027 4575);
PAINT GREEN (-6027 4575);
DISPLAY INVISIBLE (-6027 4575);
FORCEADD TAP..1
(-6025 4625);
FORCEPROP 3 LASTPIN (-6075 4625) SIG_NAME M_L_CPU0_SA_DQ<22>
J 0
(-6065 4635);
DISPLAY 0.659574 (-6065 4635);
PAINT MONO (-6065 4635);
DISPLAY INVISIBLE (-6065 4635);
FORCEPROP 1 LASTPIN (-6075 4625) BN 22
J 0
(-6087 4633);
DISPLAY 0.489362 (-6087 4633);
PAINT GREEN (-6087 4633);
FORCEPROP 2 LAST CDS_LIB mstr_standard
J 0
(-6025 4625);
DISPLAY 0.723404 (-6025 4625);
PAINT MONO (-6025 4625);
DISPLAY INVISIBLE (-6025 4625);
FORCEPROP 1 LAST BODY_TYPE PLUMBING
J 0
(-6025 4675);
DISPLAY 0.872340 (-6025 4675);
PAINT GREEN (-6025 4675);
DISPLAY INVISIBLE (-6025 4675);
FORCEPROP 1 LAST HDL_TAP TRUE
J 0
(-5700 4500);
DISPLAY 0.872340 (-5700 4500);
DISPLAY INVISIBLE (-5700 4500);
FORCEPROP 1 LAST PATH I114
J 0
(-6027 4625);
DISPLAY 0.872340 (-6027 4625);
PAINT GREEN (-6027 4625);
DISPLAY INVISIBLE (-6027 4625);
FORCEADD TAP..1
(-6025 4675);
FORCEPROP 3 LASTPIN (-6075 4675) SIG_NAME M_L_CPU0_SA_DQ<23>
J 0
(-6065 4685);
DISPLAY 0.659574 (-6065 4685);
PAINT MONO (-6065 4685);
DISPLAY INVISIBLE (-6065 4685);
FORCEPROP 1 LASTPIN (-6075 4675) BN 23
J 0
(-6087 4683);
DISPLAY 0.489362 (-6087 4683);
PAINT GREEN (-6087 4683);
FORCEPROP 2 LAST CDS_LIB mstr_standard
J 0
(-6025 4675);
DISPLAY 0.723404 (-6025 4675);
PAINT MONO (-6025 4675);
DISPLAY INVISIBLE (-6025 4675);
FORCEPROP 1 LAST BODY_TYPE PLUMBING
J 0
(-6025 4725);
DISPLAY 0.872340 (-6025 4725);
PAINT GREEN (-6025 4725);
DISPLAY INVISIBLE (-6025 4725);
FORCEPROP 1 LAST HDL_TAP TRUE
J 0
(-5700 4550);
DISPLAY 0.872340 (-5700 4550);
DISPLAY INVISIBLE (-5700 4550);
FORCEPROP 1 LAST PATH I115
J 0
(-6027 4675);
DISPLAY 0.872340 (-6027 4675);
PAINT GREEN (-6027 4675);
DISPLAY INVISIBLE (-6027 4675);
FORCEADD TAP..1
(-6025 4725);
FORCEPROP 3 LASTPIN (-6075 4725) SIG_NAME M_L_CPU0_SA_DQ<24>
J 0
(-6065 4735);
DISPLAY 0.659574 (-6065 4735);
PAINT MONO (-6065 4735);
DISPLAY INVISIBLE (-6065 4735);
FORCEPROP 1 LASTPIN (-6075 4725) BN 24
J 0
(-6087 4733);
DISPLAY 0.489362 (-6087 4733);
PAINT GREEN (-6087 4733);
FORCEPROP 2 LAST CDS_LIB mstr_standard
J 0
(-6025 4725);
DISPLAY 0.723404 (-6025 4725);
PAINT MONO (-6025 4725);
DISPLAY INVISIBLE (-6025 4725);
FORCEPROP 1 LAST BODY_TYPE PLUMBING
J 0
(-6025 4775);
DISPLAY 0.872340 (-6025 4775);
PAINT GREEN (-6025 4775);
DISPLAY INVISIBLE (-6025 4775);
FORCEPROP 1 LAST HDL_TAP TRUE
J 0
(-5700 4600);
DISPLAY 0.872340 (-5700 4600);
DISPLAY INVISIBLE (-5700 4600);
FORCEPROP 1 LAST PATH I116
J 0
(-6027 4725);
DISPLAY 0.872340 (-6027 4725);
PAINT GREEN (-6027 4725);
DISPLAY INVISIBLE (-6027 4725);
FORCEADD TAP..1
(-6025 4775);
FORCEPROP 3 LASTPIN (-6075 4775) SIG_NAME M_L_CPU0_SA_DQ<25>
J 0
(-6065 4785);
DISPLAY 0.659574 (-6065 4785);
PAINT MONO (-6065 4785);
DISPLAY INVISIBLE (-6065 4785);
FORCEPROP 1 LASTPIN (-6075 4775) BN 25
J 0
(-6087 4783);
DISPLAY 0.489362 (-6087 4783);
PAINT GREEN (-6087 4783);
FORCEPROP 2 LAST CDS_LIB mstr_standard
J 0
(-6025 4775);
DISPLAY 0.723404 (-6025 4775);
PAINT MONO (-6025 4775);
DISPLAY INVISIBLE (-6025 4775);
FORCEPROP 1 LAST BODY_TYPE PLUMBING
J 0
(-6025 4825);
DISPLAY 0.872340 (-6025 4825);
PAINT GREEN (-6025 4825);
DISPLAY INVISIBLE (-6025 4825);
FORCEPROP 1 LAST HDL_TAP TRUE
J 0
(-5700 4650);
DISPLAY 0.872340 (-5700 4650);
DISPLAY INVISIBLE (-5700 4650);
FORCEPROP 1 LAST PATH I117
J 0
(-6027 4775);
DISPLAY 0.872340 (-6027 4775);
PAINT GREEN (-6027 4775);
DISPLAY INVISIBLE (-6027 4775);
FORCEADD TAP..1
(-6025 4825);
FORCEPROP 3 LASTPIN (-6075 4825) SIG_NAME M_L_CPU0_SA_DQ<26>
J 0
(-6065 4835);
DISPLAY 0.659574 (-6065 4835);
PAINT MONO (-6065 4835);
DISPLAY INVISIBLE (-6065 4835);
FORCEPROP 1 LASTPIN (-6075 4825) BN 26
J 0
(-6087 4833);
DISPLAY 0.489362 (-6087 4833);
PAINT GREEN (-6087 4833);
FORCEPROP 2 LAST CDS_LIB mstr_standard
J 0
(-6025 4825);
DISPLAY 0.723404 (-6025 4825);
PAINT MONO (-6025 4825);
DISPLAY INVISIBLE (-6025 4825);
FORCEPROP 1 LAST BODY_TYPE PLUMBING
J 0
(-6025 4875);
DISPLAY 0.872340 (-6025 4875);
PAINT GREEN (-6025 4875);
DISPLAY INVISIBLE (-6025 4875);
FORCEPROP 1 LAST HDL_TAP TRUE
J 0
(-5700 4700);
DISPLAY 0.872340 (-5700 4700);
DISPLAY INVISIBLE (-5700 4700);
FORCEPROP 1 LAST PATH I118
J 0
(-6027 4825);
DISPLAY 0.872340 (-6027 4825);
PAINT GREEN (-6027 4825);
DISPLAY INVISIBLE (-6027 4825);
FORCEADD TAP..1
(-6025 4875);
FORCEPROP 3 LASTPIN (-6075 4875) SIG_NAME M_L_CPU0_SA_DQ<27>
J 0
(-6065 4885);
DISPLAY 0.659574 (-6065 4885);
PAINT MONO (-6065 4885);
DISPLAY INVISIBLE (-6065 4885);
FORCEPROP 1 LASTPIN (-6075 4875) BN 27
J 0
(-6087 4883);
DISPLAY 0.489362 (-6087 4883);
PAINT GREEN (-6087 4883);
FORCEPROP 2 LAST CDS_LIB mstr_standard
J 0
(-6025 4875);
DISPLAY 0.723404 (-6025 4875);
PAINT MONO (-6025 4875);
DISPLAY INVISIBLE (-6025 4875);
FORCEPROP 1 LAST BODY_TYPE PLUMBING
J 0
(-6025 4925);
DISPLAY 0.872340 (-6025 4925);
PAINT GREEN (-6025 4925);
DISPLAY INVISIBLE (-6025 4925);
FORCEPROP 1 LAST HDL_TAP TRUE
J 0
(-5700 4750);
DISPLAY 0.872340 (-5700 4750);
DISPLAY INVISIBLE (-5700 4750);
FORCEPROP 1 LAST PATH I119
J 0
(-6027 4875);
DISPLAY 0.872340 (-6027 4875);
PAINT GREEN (-6027 4875);
DISPLAY INVISIBLE (-6027 4875);
FORCEADD OFFPAGE..1
(-8325 3775);
FORCEPROP 2 LAST $XR0 21 
J 0
(-8546 3775);
DISPLAY 0.638298 (-8546 3775);
PAINT MONO (-8546 3775);
FORCEPROP 2 LAST CDS_LIB mstr_standard
J 0
(-8325 3775);
DISPLAY 0.808511 (-8325 3775);
DISPLAY INVISIBLE (-8325 3775);
FORCEPROP 1 LAST OFFPAGE TRUE
J 0
(-8000 3650);
DISPLAY 0.872340 (-8000 3650);
PAINT GREEN (-8000 3650);
DISPLAY INVISIBLE (-8000 3650);
FORCEPROP 1 LAST COMMENT_BODY TRUE
J 0
(-8200 3675);
DISPLAY 0.872340 (-8200 3675);
PAINT GREEN (-8200 3675);
DISPLAY INVISIBLE (-8200 3675);
FORCEPROP 2 LAST PATH I12
J 0
(-8275 3850);
DISPLAY 1.021277 (-8275 3850);
DISPLAY INVISIBLE (-8275 3850);
FORCEADD TAP..1
(-6025 4925);
FORCEPROP 3 LASTPIN (-6075 4925) SIG_NAME M_L_CPU0_SA_DQ<28>
J 0
(-6065 4935);
DISPLAY 0.659574 (-6065 4935);
PAINT MONO (-6065 4935);
DISPLAY INVISIBLE (-6065 4935);
FORCEPROP 1 LASTPIN (-6075 4925) BN 28
J 0
(-6087 4933);
DISPLAY 0.489362 (-6087 4933);
PAINT GREEN (-6087 4933);
FORCEPROP 2 LAST CDS_LIB mstr_standard
J 0
(-6025 4925);
DISPLAY 0.723404 (-6025 4925);
PAINT MONO (-6025 4925);
DISPLAY INVISIBLE (-6025 4925);
FORCEPROP 1 LAST BODY_TYPE PLUMBING
J 0
(-6025 4975);
DISPLAY 0.872340 (-6025 4975);
PAINT GREEN (-6025 4975);
DISPLAY INVISIBLE (-6025 4975);
FORCEPROP 1 LAST HDL_TAP TRUE
J 0
(-5700 4800);
DISPLAY 0.872340 (-5700 4800);
DISPLAY INVISIBLE (-5700 4800);
FORCEPROP 1 LAST PATH I120
J 0
(-6027 4925);
DISPLAY 0.872340 (-6027 4925);
PAINT GREEN (-6027 4925);
DISPLAY INVISIBLE (-6027 4925);
FORCEADD TAP..1
(-6025 5025);
FORCEPROP 3 LASTPIN (-6075 5025) SIG_NAME M_L_CPU0_SA_DQ<30>
J 0
(-6065 5035);
DISPLAY 0.659574 (-6065 5035);
PAINT MONO (-6065 5035);
DISPLAY INVISIBLE (-6065 5035);
FORCEPROP 1 LASTPIN (-6075 5025) BN 30
J 0
(-6087 5033);
DISPLAY 0.489362 (-6087 5033);
PAINT GREEN (-6087 5033);
FORCEPROP 2 LAST CDS_LIB mstr_standard
J 0
(-6025 5025);
DISPLAY 0.723404 (-6025 5025);
PAINT MONO (-6025 5025);
DISPLAY INVISIBLE (-6025 5025);
FORCEPROP 1 LAST BODY_TYPE PLUMBING
J 0
(-6025 5075);
DISPLAY 0.872340 (-6025 5075);
PAINT GREEN (-6025 5075);
DISPLAY INVISIBLE (-6025 5075);
FORCEPROP 1 LAST HDL_TAP TRUE
J 0
(-5700 4900);
DISPLAY 0.872340 (-5700 4900);
DISPLAY INVISIBLE (-5700 4900);
FORCEPROP 1 LAST PATH I121
J 0
(-6027 5025);
DISPLAY 0.872340 (-6027 5025);
PAINT GREEN (-6027 5025);
DISPLAY INVISIBLE (-6027 5025);
FORCEADD TAP..1
(-6025 5075);
FORCEPROP 3 LASTPIN (-6075 5075) SIG_NAME M_L_CPU0_SA_DQ<31>
J 0
(-6065 5085);
DISPLAY 0.659574 (-6065 5085);
PAINT MONO (-6065 5085);
DISPLAY INVISIBLE (-6065 5085);
FORCEPROP 1 LASTPIN (-6075 5075) BN 31
J 0
(-6087 5083);
DISPLAY 0.489362 (-6087 5083);
PAINT GREEN (-6087 5083);
FORCEPROP 2 LAST CDS_LIB mstr_standard
J 0
(-6025 5075);
DISPLAY 0.723404 (-6025 5075);
PAINT MONO (-6025 5075);
DISPLAY INVISIBLE (-6025 5075);
FORCEPROP 1 LAST BODY_TYPE PLUMBING
J 0
(-6025 5125);
DISPLAY 0.872340 (-6025 5125);
PAINT GREEN (-6025 5125);
DISPLAY INVISIBLE (-6025 5125);
FORCEPROP 1 LAST HDL_TAP TRUE
J 0
(-5700 4950);
DISPLAY 0.872340 (-5700 4950);
DISPLAY INVISIBLE (-5700 4950);
FORCEPROP 1 LAST PATH I122
J 0
(-6027 5075);
DISPLAY 0.872340 (-6027 5075);
PAINT GREEN (-6027 5075);
DISPLAY INVISIBLE (-6027 5075);
FORCEADD TAP..1
(-6025 4975);
FORCEPROP 3 LASTPIN (-6075 4975) SIG_NAME M_L_CPU0_SA_DQ<29>
J 0
(-6065 4985);
DISPLAY 0.659574 (-6065 4985);
PAINT MONO (-6065 4985);
DISPLAY INVISIBLE (-6065 4985);
FORCEPROP 1 LASTPIN (-6075 4975) BN 29
J 0
(-6087 4983);
DISPLAY 0.489362 (-6087 4983);
PAINT GREEN (-6087 4983);
FORCEPROP 2 LAST CDS_LIB mstr_standard
J 0
(-6025 4975);
DISPLAY 0.723404 (-6025 4975);
PAINT MONO (-6025 4975);
DISPLAY INVISIBLE (-6025 4975);
FORCEPROP 1 LAST BODY_TYPE PLUMBING
J 0
(-6025 5025);
DISPLAY 0.872340 (-6025 5025);
PAINT GREEN (-6025 5025);
DISPLAY INVISIBLE (-6025 5025);
FORCEPROP 1 LAST HDL_TAP TRUE
J 0
(-5700 4850);
DISPLAY 0.872340 (-5700 4850);
DISPLAY INVISIBLE (-5700 4850);
FORCEPROP 1 LAST PATH I123
J 0
(-6027 4975);
DISPLAY 0.872340 (-6027 4975);
PAINT GREEN (-6027 4975);
DISPLAY INVISIBLE (-6027 4975);
FORCEADD OFFPAGE..3
(-5350 3450);
FORCEPROP 2 LAST $XR0 21 
J 0
(-5136 3450);
DISPLAY 0.638298 (-5136 3450);
PAINT MONO (-5136 3450);
FORCEPROP 2 LAST CDS_LIB mstr_standard
J 0
(-5350 3450);
DISPLAY 0.723404 (-5350 3450);
PAINT MONO (-5350 3450);
DISPLAY INVISIBLE (-5350 3450);
FORCEPROP 1 LAST OFFPAGE TRUE
J 0
(-5025 3325);
DISPLAY 0.872340 (-5025 3325);
PAINT GREEN (-5025 3325);
DISPLAY INVISIBLE (-5025 3325);
FORCEPROP 1 LAST COMMENT_BODY TRUE
J 0
(-5400 3350);
DISPLAY 0.872340 (-5400 3350);
PAINT GREEN (-5400 3350);
DISPLAY INVISIBLE (-5400 3350);
FORCEPROP 2 LAST PATH I124
J 0
(-5150 3525);
DISPLAY 1.021277 (-5150 3525);
DISPLAY INVISIBLE (-5150 3525);
FORCEADD OFFPAGE..3
(-5350 5100);
FORCEPROP 2 LAST $XR0 21 
J 0
(-5136 5100);
DISPLAY 0.638298 (-5136 5100);
PAINT MONO (-5136 5100);
FORCEPROP 2 LAST CDS_LIB mstr_standard
J 0
(-5350 5100);
DISPLAY 0.723404 (-5350 5100);
PAINT MONO (-5350 5100);
DISPLAY INVISIBLE (-5350 5100);
FORCEPROP 1 LAST OFFPAGE TRUE
J 0
(-5025 4975);
DISPLAY 0.872340 (-5025 4975);
PAINT GREEN (-5025 4975);
DISPLAY INVISIBLE (-5025 4975);
FORCEPROP 1 LAST COMMENT_BODY TRUE
J 0
(-5400 5000);
DISPLAY 0.872340 (-5400 5000);
PAINT GREEN (-5400 5000);
DISPLAY INVISIBLE (-5400 5000);
FORCEPROP 2 LAST PATH I125
J 0
(-5150 5175);
DISPLAY 1.021277 (-5150 5175);
DISPLAY INVISIBLE (-5150 5175);
FORCEADD GND..1
(-6450 700);
FORCEPROP 3 LASTPIN (-6450 750) SIG_NAME GND\g
J 0
(-6440 760);
DISPLAY 0.659574 (-6440 760);
PAINT MONO (-6440 760);
DISPLAY INVISIBLE (-6440 760);
FORCEPROP 2 LAST BOM_COST MEM
J 0
(-6550 775);
DISPLAY 0.808511 (-6550 775);
DISPLAY INVISIBLE (-6550 775);
FORCEPROP 1 LAST SIZE 1B
J 0
(-6375 650);
DISPLAY 0.851064 (-6375 650);
PAINT GREEN (-6375 650);
DISPLAY INVISIBLE (-6375 650);
FORCEPROP 2 LAST CDS_LIB mstr_symbols
J 0
(-6450 700);
DISPLAY 0.808511 (-6450 700);
DISPLAY INVISIBLE (-6450 700);
FORCEPROP 1 LAST VOLTAGE 0.0
J 0
(-6495 657);
DISPLAY 0.723404 (-6495 657);
PAINT SKYBLUE (-6495 657);
DISPLAY INVISIBLE (-6495 657);
FORCEPROP 1 LAST BODY_TYPE PLUMBING
J 0
(-6495 657);
DISPLAY 0.340426 (-6495 657);
PAINT GREEN (-6495 657);
DISPLAY INVISIBLE (-6495 657);
FORCEPROP 1 LAST HDL_POWER GND
J 0
(-6450 850);
DISPLAY 0.851064 (-6450 850);
PAINT GREEN (-6450 850);
DISPLAY INVISIBLE (-6450 850);
FORCEPROP 1 LAST PATH I126
J 0
(-6375 700);
DISPLAY 0.872340 (-6375 700);
PAINT AQUA (-6375 700);
DISPLAY INVISIBLE (-6375 700);
FORCEADD Q_RES..2
(-6450 925);
FORCEPROP 1 LAST LOCATION R769
J 0
(-6405 1050);
DISPLAY 0.489362 (-6405 1050);
PAINT SKYBLUE (-6405 1050);
FORCEPROP 0 LAST $SEC 1
J 0
(-6400 1100);
DISPLAY 0.680851 (-6400 1100);
PAINT MONO (-6400 1100);
DISPLAY INVISIBLE (-6400 1100);
FORCEPROP 0 LAST CDS_SEC 1
J 0
(-6400 1100);
DISPLAY 1.021277 (-6400 1100);
DISPLAY INVISIBLE (-6400 1100);
FORCEPROP 1 LASTPIN (-6450 1025) $PN 1
J 0
(-6445 987);
DISPLAY 0.489362 (-6445 987);
PAINT MONO (-6445 987);
FORCEPROP 1 LASTPIN (-6450 825) $PN 2
J 0
(-6445 835);
DISPLAY 0.489362 (-6445 835);
PAINT MONO (-6445 835);
FORCEPROP 1 LAST WATTAGE 1/16W
J 0
(-6410 900);
DISPLAY 0.489362 (-6410 900);
PAINT SKYBLUE (-6410 900);
FORCEPROP 1 LAST MATERIAL CHIP
J 0
(-6410 850);
DISPLAY 0.489362 (-6410 850);
PAINT SKYBLUE (-6410 850);
FORCEPROP 1 LAST TOLERANCE 1%
J 0
(-6405 950);
DISPLAY 0.489362 (-6405 950);
PAINT SKYBLUE (-6405 950);
FORCEPROP 1 LAST VALUE 84.5K
J 0
(-6405 1000);
DISPLAY 0.489362 (-6405 1000);
PAINT SKYBLUE (-6405 1000);
FORCEPROP 1 LAST PACK_TYPE 0402LF
J 0
(-6410 750);
DISPLAY 0.489362 (-6410 750);
PAINT SKYBLUE (-6410 750);
FORCEPROP 2 LAST CDS_LIB pure_quanta
J 0
(-6450 925);
DISPLAY INVISIBLE (-6450 925);
FORCEPROP 1 LAST PATH I127
J 0
(-6400 1100);
DISPLAY 0.978723 (-6400 1100);
PAINT WHITE (-6400 1100);
DISPLAY INVISIBLE (-6400 1100);
FORCEPROP 1 LAST PART_NUMBER CS38452FB05
J 0
(-6410 800);
DISPLAY 0.489362 (-6410 800);
PAINT SKYBLUE (-6410 800);
DISPLAY INVISIBLE (-6410 800);
FORCEADD OFFPAGE..5
(-7225 1100);
FORCEPROP 2 LAST $XR0 97 
J 0
(-7449 1100);
DISPLAY 0.638298 (-7449 1100);
PAINT MONO (-7449 1100);
FORCEPROP 2 LAST BOM_COST MEM
J 0
(-7300 1175);
DISPLAY 0.808511 (-7300 1175);
DISPLAY INVISIBLE (-7300 1175);
FORCEPROP 2 LAST CDS_LIB mstr_standard
J 0
(-7225 1100);
DISPLAY 0.808511 (-7225 1100);
DISPLAY INVISIBLE (-7225 1100);
FORCEPROP 1 LAST OFFPAGE TRUE
J 0
(-6900 975);
DISPLAY 0.872340 (-6900 975);
PAINT GREEN (-6900 975);
DISPLAY INVISIBLE (-6900 975);
FORCEPROP 1 LAST COMMENT_BODY TRUE
J 0
(-7125 1025);
DISPLAY 0.872340 (-7125 1025);
PAINT GREEN (-7125 1025);
DISPLAY INVISIBLE (-7125 1025);
FORCEPROP 2 LAST PATH I128
J 0
(-7475 1150);
DISPLAY 1.021277 (-7475 1150);
DISPLAY INVISIBLE (-7475 1150);
FORCEADD OFFPAGE..6
(-8325 3725);
FORCEPROP 2 LAST $XR0 21 
J 0
(-8574 3725);
DISPLAY 0.638298 (-8574 3725);
PAINT MONO (-8574 3725);
FORCEPROP 2 LAST CDS_LIB mstr_standard
J 0
(-8325 3725);
DISPLAY 0.723404 (-8325 3725);
PAINT MONO (-8325 3725);
DISPLAY INVISIBLE (-8325 3725);
FORCEPROP 1 LAST OFFPAGE TRUE
J 0
(-8000 3600);
DISPLAY 0.872340 (-8000 3600);
PAINT GREEN (-8000 3600);
DISPLAY INVISIBLE (-8000 3600);
FORCEPROP 1 LAST COMMENT_BODY TRUE
J 0
(-8225 3650);
DISPLAY 0.872340 (-8225 3650);
PAINT GREEN (-8225 3650);
DISPLAY INVISIBLE (-8225 3650);
FORCEPROP 2 LAST PATH I13
J 0
(-8275 3800);
DISPLAY 1.021277 (-8275 3800);
DISPLAY INVISIBLE (-8275 3800);
FORCEADD GND..1
(-2200 1750);
FORCEPROP 3 LASTPIN (-2200 1800) SIG_NAME GND\g
J 0
(-2190 1810);
DISPLAY 0.659574 (-2190 1810);
PAINT MONO (-2190 1810);
DISPLAY INVISIBLE (-2190 1810);
FORCEPROP 2 LAST CDS_LIB mstr_symbols
J 0
(-2200 1750);
DISPLAY 0.723404 (-2200 1750);
DISPLAY INVISIBLE (-2200 1750);
FORCEPROP 1 LAST SIZE 1B
J 0
(-2125 1700);
DISPLAY 0.851064 (-2125 1700);
PAINT GREEN (-2125 1700);
DISPLAY INVISIBLE (-2125 1700);
FORCEPROP 1 LAST VOLTAGE 0.0
J 0
(-2245 1707);
DISPLAY 0.723404 (-2245 1707);
PAINT SKYBLUE (-2245 1707);
DISPLAY INVISIBLE (-2245 1707);
FORCEPROP 1 LAST BODY_TYPE PLUMBING
J 0
(-2245 1707);
DISPLAY 0.340426 (-2245 1707);
PAINT GREEN (-2245 1707);
DISPLAY INVISIBLE (-2245 1707);
FORCEPROP 1 LAST HDL_POWER GND
J 0
(-2200 1900);
DISPLAY 0.851064 (-2200 1900);
PAINT GREEN (-2200 1900);
DISPLAY INVISIBLE (-2200 1900);
FORCEPROP 1 LAST PATH I138
J 0
(-2125 1750);
DISPLAY 0.872340 (-2125 1750);
PAINT AQUA (-2125 1750);
DISPLAY INVISIBLE (-2125 1750);
FORCEADD GND..1
(-400 1525);
FORCEPROP 3 LASTPIN (-400 1575) SIG_NAME GND\g
J 0
(-390 1585);
DISPLAY 0.659574 (-390 1585);
PAINT MONO (-390 1585);
DISPLAY INVISIBLE (-390 1585);
FORCEPROP 2 LAST CDS_LIB mstr_symbols
J 0
(-400 1525);
DISPLAY 0.723404 (-400 1525);
DISPLAY INVISIBLE (-400 1525);
FORCEPROP 1 LAST SIZE 1B
J 0
(-325 1475);
DISPLAY 0.851064 (-325 1475);
PAINT GREEN (-325 1475);
DISPLAY INVISIBLE (-325 1475);
FORCEPROP 1 LAST VOLTAGE 0.0
J 0
(-445 1482);
DISPLAY 0.723404 (-445 1482);
PAINT SKYBLUE (-445 1482);
DISPLAY INVISIBLE (-445 1482);
FORCEPROP 1 LAST BODY_TYPE PLUMBING
J 0
(-445 1482);
DISPLAY 0.340426 (-445 1482);
PAINT GREEN (-445 1482);
DISPLAY INVISIBLE (-445 1482);
FORCEPROP 1 LAST HDL_POWER GND
J 0
(-400 1675);
DISPLAY 0.851064 (-400 1675);
PAINT GREEN (-400 1675);
DISPLAY INVISIBLE (-400 1675);
FORCEPROP 1 LAST PATH I139
J 0
(-325 1525);
DISPLAY 0.872340 (-325 1525);
PAINT AQUA (-325 1525);
DISPLAY INVISIBLE (-325 1525);
FORCEADD OFFPAGE..1
(-8325 3925);
FORCEPROP 2 LAST $XR0 21 
J 0
(-8546 3925);
DISPLAY 0.638298 (-8546 3925);
PAINT MONO (-8546 3925);
FORCEPROP 2 LAST CDS_LIB mstr_standard
J 0
(-8325 3925);
DISPLAY 0.808511 (-8325 3925);
DISPLAY INVISIBLE (-8325 3925);
FORCEPROP 1 LAST OFFPAGE TRUE
J 0
(-8000 3800);
DISPLAY 0.872340 (-8000 3800);
PAINT GREEN (-8000 3800);
DISPLAY INVISIBLE (-8000 3800);
FORCEPROP 1 LAST COMMENT_BODY TRUE
J 0
(-8200 3825);
DISPLAY 0.872340 (-8200 3825);
PAINT GREEN (-8200 3825);
DISPLAY INVISIBLE (-8200 3825);
FORCEPROP 2 LAST PATH I14
J 0
(-8275 4000);
DISPLAY 1.021277 (-8275 4000);
DISPLAY INVISIBLE (-8275 4000);
FORCEADD SCONN288_DDR506112002KQ..3
(-1300 3525);
FORCEPROP 1 LAST LOCATION J67
J 0
(-1750 5500);
DISPLAY 0.468085 (-1750 5500);
PAINT SKYBLUE (-1750 5500);
FORCEPROP 0 LAST $SEC 3
J 0
(-1750 5650);
DISPLAY 0.680851 (-1750 5650);
PAINT MONO (-1750 5650);
DISPLAY INVISIBLE (-1750 5650);
FORCEPROP 2 LAST CDS_SEC 3
J 0
(-1750 5650);
DISPLAY 1.021277 (-1750 5650);
DISPLAY INVISIBLE (-1750 5650);
FORCEPROP 0 LASTPIN (-700 1925) $PN G1
J 0
(-690 1935);
DISPLAY 0.680851 (-690 1935);
PAINT MONO (-690 1935);
FORCEPROP 0 LASTPIN (-700 1875) $PN G2
J 0
(-690 1885);
DISPLAY 0.680851 (-690 1885);
PAINT MONO (-690 1885);
FORCEPROP 0 LASTPIN (-700 1825) $PN G3
J 0
(-690 1835);
DISPLAY 0.680851 (-690 1835);
PAINT MONO (-690 1835);
FORCEPROP 0 LASTPIN (-1900 5075) $PN 1
J 2
(-1910 5085);
DISPLAY 0.680851 (-1910 5085);
PAINT MONO (-1910 5085);
FORCEPROP 0 LASTPIN (-1900 5125) $PN 145
J 2
(-1910 5135);
DISPLAY 0.680851 (-1910 5135);
PAINT MONO (-1910 5135);
FORCEPROP 0 LASTPIN (-1900 5175) $PN 146
J 2
(-1910 5185);
DISPLAY 0.680851 (-1910 5185);
PAINT MONO (-1910 5185);
FORCEPROP 0 LASTPIN (-700 2025) $PN 6
J 0
(-690 2035);
DISPLAY 0.680851 (-690 2035);
PAINT MONO (-690 2035);
FORCEPROP 0 LASTPIN (-700 2075) $PN 8
J 0
(-690 2085);
DISPLAY 0.680851 (-690 2085);
PAINT MONO (-690 2085);
FORCEPROP 0 LASTPIN (-700 2125) $PN 10
J 0
(-690 2135);
DISPLAY 0.680851 (-690 2135);
PAINT MONO (-690 2135);
FORCEPROP 0 LASTPIN (-700 2175) $PN 13
J 0
(-690 2185);
DISPLAY 0.680851 (-690 2185);
PAINT MONO (-690 2185);
FORCEPROP 0 LASTPIN (-700 2225) $PN 15
J 0
(-690 2235);
DISPLAY 0.680851 (-690 2235);
PAINT MONO (-690 2235);
FORCEPROP 0 LASTPIN (-700 2275) $PN 17
J 0
(-690 2285);
DISPLAY 0.680851 (-690 2285);
PAINT MONO (-690 2285);
FORCEPROP 0 LASTPIN (-700 2325) $PN 19
J 0
(-690 2335);
DISPLAY 0.680851 (-690 2335);
PAINT MONO (-690 2335);
FORCEPROP 0 LASTPIN (-700 2375) $PN 21
J 0
(-690 2385);
DISPLAY 0.680851 (-690 2385);
PAINT MONO (-690 2385);
FORCEPROP 0 LASTPIN (-700 2425) $PN 24
J 0
(-690 2435);
DISPLAY 0.680851 (-690 2435);
PAINT MONO (-690 2435);
FORCEPROP 0 LASTPIN (-700 2475) $PN 26
J 0
(-690 2485);
DISPLAY 0.680851 (-690 2485);
PAINT MONO (-690 2485);
FORCEPROP 0 LASTPIN (-700 2525) $PN 28
J 0
(-690 2535);
DISPLAY 0.680851 (-690 2535);
PAINT MONO (-690 2535);
FORCEPROP 0 LASTPIN (-700 2575) $PN 30
J 0
(-690 2585);
DISPLAY 0.680851 (-690 2585);
PAINT MONO (-690 2585);
FORCEPROP 0 LASTPIN (-700 2625) $PN 32
J 0
(-690 2635);
DISPLAY 0.680851 (-690 2635);
PAINT MONO (-690 2635);
FORCEPROP 0 LASTPIN (-700 2675) $PN 35
J 0
(-690 2685);
DISPLAY 0.680851 (-690 2685);
PAINT MONO (-690 2685);
FORCEPROP 0 LASTPIN (-700 2725) $PN 37
J 0
(-690 2735);
DISPLAY 0.680851 (-690 2735);
PAINT MONO (-690 2735);
FORCEPROP 0 LASTPIN (-700 2775) $PN 39
J 0
(-690 2785);
DISPLAY 0.680851 (-690 2785);
PAINT MONO (-690 2785);
FORCEPROP 0 LASTPIN (-700 2825) $PN 41
J 0
(-690 2835);
DISPLAY 0.680851 (-690 2835);
PAINT MONO (-690 2835);
FORCEPROP 0 LASTPIN (-700 2875) $PN 43
J 0
(-690 2885);
DISPLAY 0.680851 (-690 2885);
PAINT MONO (-690 2885);
FORCEPROP 0 LASTPIN (-700 2925) $PN 46
J 0
(-690 2935);
DISPLAY 0.680851 (-690 2935);
PAINT MONO (-690 2935);
FORCEPROP 0 LASTPIN (-700 2975) $PN 48
J 0
(-690 2985);
DISPLAY 0.680851 (-690 2985);
PAINT MONO (-690 2985);
FORCEPROP 0 LASTPIN (-700 3025) $PN 50
J 0
(-690 3035);
DISPLAY 0.680851 (-690 3035);
PAINT MONO (-690 3035);
FORCEPROP 0 LASTPIN (-700 3075) $PN 52
J 0
(-690 3085);
DISPLAY 0.680851 (-690 3085);
PAINT MONO (-690 3085);
FORCEPROP 0 LASTPIN (-700 3125) $PN 54
J 0
(-690 3135);
DISPLAY 0.680851 (-690 3135);
PAINT MONO (-690 3135);
FORCEPROP 0 LASTPIN (-700 3175) $PN 57
J 0
(-690 3185);
DISPLAY 0.680851 (-690 3185);
PAINT MONO (-690 3185);
FORCEPROP 0 LASTPIN (-700 3225) $PN 59
J 0
(-690 3235);
DISPLAY 0.680851 (-690 3235);
PAINT MONO (-690 3235);
FORCEPROP 0 LASTPIN (-700 3275) $PN 61
J 0
(-690 3285);
DISPLAY 0.680851 (-690 3285);
PAINT MONO (-690 3285);
FORCEPROP 0 LASTPIN (-700 3325) $PN 63
J 0
(-690 3335);
DISPLAY 0.680851 (-690 3335);
PAINT MONO (-690 3335);
FORCEPROP 0 LASTPIN (-700 3375) $PN 65
J 0
(-690 3385);
DISPLAY 0.680851 (-690 3385);
PAINT MONO (-690 3385);
FORCEPROP 0 LASTPIN (-700 3425) $PN 67
J 0
(-690 3435);
DISPLAY 0.680851 (-690 3435);
PAINT MONO (-690 3435);
FORCEPROP 0 LASTPIN (-700 3475) $PN 69
J 0
(-690 3485);
DISPLAY 0.680851 (-690 3485);
PAINT MONO (-690 3485);
FORCEPROP 0 LASTPIN (-700 3525) $PN 71
J 0
(-690 3535);
DISPLAY 0.680851 (-690 3535);
PAINT MONO (-690 3535);
FORCEPROP 0 LASTPIN (-700 3575) $PN 73
J 0
(-690 3585);
DISPLAY 0.680851 (-690 3585);
PAINT MONO (-690 3585);
FORCEPROP 0 LASTPIN (-700 3625) $PN 75
J 0
(-690 3635);
DISPLAY 0.680851 (-690 3635);
PAINT MONO (-690 3635);
FORCEPROP 0 LASTPIN (-700 3675) $PN 77
J 0
(-690 3685);
DISPLAY 0.680851 (-690 3685);
PAINT MONO (-690 3685);
FORCEPROP 0 LASTPIN (-700 3725) $PN 79
J 0
(-690 3735);
DISPLAY 0.680851 (-690 3735);
PAINT MONO (-690 3735);
FORCEPROP 0 LASTPIN (-700 3775) $PN 81
J 0
(-690 3785);
DISPLAY 0.680851 (-690 3785);
PAINT MONO (-690 3785);
FORCEPROP 0 LASTPIN (-700 3825) $PN 83
J 0
(-690 3835);
DISPLAY 0.680851 (-690 3835);
PAINT MONO (-690 3835);
FORCEPROP 0 LASTPIN (-700 3875) $PN 85
J 0
(-690 3885);
DISPLAY 0.680851 (-690 3885);
PAINT MONO (-690 3885);
FORCEPROP 0 LASTPIN (-700 3925) $PN 88
J 0
(-690 3935);
DISPLAY 0.680851 (-690 3935);
PAINT MONO (-690 3935);
FORCEPROP 0 LASTPIN (-700 3975) $PN 90
J 0
(-690 3985);
DISPLAY 0.680851 (-690 3985);
PAINT MONO (-690 3985);
FORCEPROP 0 LASTPIN (-700 4025) $PN 92
J 0
(-690 4035);
DISPLAY 0.680851 (-690 4035);
PAINT MONO (-690 4035);
FORCEPROP 0 LASTPIN (-700 4075) $PN 95
J 0
(-690 4085);
DISPLAY 0.680851 (-690 4085);
PAINT MONO (-690 4085);
FORCEPROP 0 LASTPIN (-700 4125) $PN 97
J 0
(-690 4135);
DISPLAY 0.680851 (-690 4135);
PAINT MONO (-690 4135);
FORCEPROP 0 LASTPIN (-700 4175) $PN 99
J 0
(-690 4185);
DISPLAY 0.680851 (-690 4185);
PAINT MONO (-690 4185);
FORCEPROP 0 LASTPIN (-700 4225) $PN 101
J 0
(-690 4235);
DISPLAY 0.680851 (-690 4235);
PAINT MONO (-690 4235);
FORCEPROP 0 LASTPIN (-700 4275) $PN 103
J 0
(-690 4285);
DISPLAY 0.680851 (-690 4285);
PAINT MONO (-690 4285);
FORCEPROP 0 LASTPIN (-700 4325) $PN 106
J 0
(-690 4335);
DISPLAY 0.680851 (-690 4335);
PAINT MONO (-690 4335);
FORCEPROP 0 LASTPIN (-700 4375) $PN 108
J 0
(-690 4385);
DISPLAY 0.680851 (-690 4385);
PAINT MONO (-690 4385);
FORCEPROP 0 LASTPIN (-700 4425) $PN 110
J 0
(-690 4435);
DISPLAY 0.680851 (-690 4435);
PAINT MONO (-690 4435);
FORCEPROP 0 LASTPIN (-700 4475) $PN 112
J 0
(-690 4485);
DISPLAY 0.680851 (-690 4485);
PAINT MONO (-690 4485);
FORCEPROP 0 LASTPIN (-700 4525) $PN 114
J 0
(-690 4535);
DISPLAY 0.680851 (-690 4535);
PAINT MONO (-690 4535);
FORCEPROP 0 LASTPIN (-700 4575) $PN 117
J 0
(-690 4585);
DISPLAY 0.680851 (-690 4585);
PAINT MONO (-690 4585);
FORCEPROP 0 LASTPIN (-700 4625) $PN 119
J 0
(-690 4635);
DISPLAY 0.680851 (-690 4635);
PAINT MONO (-690 4635);
FORCEPROP 0 LASTPIN (-700 4675) $PN 121
J 0
(-690 4685);
DISPLAY 0.680851 (-690 4685);
PAINT MONO (-690 4685);
FORCEPROP 0 LASTPIN (-700 4725) $PN 123
J 0
(-690 4735);
DISPLAY 0.680851 (-690 4735);
PAINT MONO (-690 4735);
FORCEPROP 0 LASTPIN (-700 4775) $PN 125
J 0
(-690 4785);
DISPLAY 0.680851 (-690 4785);
PAINT MONO (-690 4785);
FORCEPROP 0 LASTPIN (-700 4825) $PN 128
J 0
(-690 4835);
DISPLAY 0.680851 (-690 4835);
PAINT MONO (-690 4835);
FORCEPROP 0 LASTPIN (-700 4875) $PN 130
J 0
(-690 4885);
DISPLAY 0.680851 (-690 4885);
PAINT MONO (-690 4885);
FORCEPROP 0 LASTPIN (-700 4925) $PN 132
J 0
(-690 4935);
DISPLAY 0.680851 (-690 4935);
PAINT MONO (-690 4935);
FORCEPROP 0 LASTPIN (-700 4975) $PN 134
J 0
(-690 4985);
DISPLAY 0.680851 (-690 4985);
PAINT MONO (-690 4985);
FORCEPROP 0 LASTPIN (-700 5025) $PN 136
J 0
(-690 5035);
DISPLAY 0.680851 (-690 5035);
PAINT MONO (-690 5035);
FORCEPROP 0 LASTPIN (-700 5075) $PN 139
J 0
(-690 5085);
DISPLAY 0.680851 (-690 5085);
PAINT MONO (-690 5085);
FORCEPROP 0 LASTPIN (-700 5125) $PN 141
J 0
(-690 5135);
DISPLAY 0.680851 (-690 5135);
PAINT MONO (-690 5135);
FORCEPROP 0 LASTPIN (-700 5175) $PN 143
J 0
(-690 5185);
DISPLAY 0.680851 (-690 5185);
PAINT MONO (-690 5185);
FORCEPROP 0 LASTPIN (-1900 1925) $PN 151
J 2
(-1910 1935);
DISPLAY 0.680851 (-1910 1935);
PAINT MONO (-1910 1935);
FORCEPROP 0 LASTPIN (-1900 1975) $PN 153
J 2
(-1910 1985);
DISPLAY 0.680851 (-1910 1985);
PAINT MONO (-1910 1985);
FORCEPROP 0 LASTPIN (-1900 2025) $PN 155
J 2
(-1910 2035);
DISPLAY 0.680851 (-1910 2035);
PAINT MONO (-1910 2035);
FORCEPROP 0 LASTPIN (-1900 2075) $PN 158
J 2
(-1910 2085);
DISPLAY 0.680851 (-1910 2085);
PAINT MONO (-1910 2085);
FORCEPROP 0 LASTPIN (-1900 2125) $PN 160
J 2
(-1910 2135);
DISPLAY 0.680851 (-1910 2135);
PAINT MONO (-1910 2135);
FORCEPROP 0 LASTPIN (-1900 2175) $PN 162
J 2
(-1910 2185);
DISPLAY 0.680851 (-1910 2185);
PAINT MONO (-1910 2185);
FORCEPROP 0 LASTPIN (-1900 2225) $PN 164
J 2
(-1910 2235);
DISPLAY 0.680851 (-1910 2235);
PAINT MONO (-1910 2235);
FORCEPROP 0 LASTPIN (-1900 2275) $PN 166
J 2
(-1910 2285);
DISPLAY 0.680851 (-1910 2285);
PAINT MONO (-1910 2285);
FORCEPROP 0 LASTPIN (-1900 2325) $PN 169
J 2
(-1910 2335);
DISPLAY 0.680851 (-1910 2335);
PAINT MONO (-1910 2335);
FORCEPROP 0 LASTPIN (-1900 2375) $PN 171
J 2
(-1910 2385);
DISPLAY 0.680851 (-1910 2385);
PAINT MONO (-1910 2385);
FORCEPROP 0 LASTPIN (-1900 2425) $PN 173
J 2
(-1910 2435);
DISPLAY 0.680851 (-1910 2435);
PAINT MONO (-1910 2435);
FORCEPROP 0 LASTPIN (-1900 2475) $PN 175
J 2
(-1910 2485);
DISPLAY 0.680851 (-1910 2485);
PAINT MONO (-1910 2485);
FORCEPROP 0 LASTPIN (-1900 2525) $PN 177
J 2
(-1910 2535);
DISPLAY 0.680851 (-1910 2535);
PAINT MONO (-1910 2535);
FORCEPROP 0 LASTPIN (-1900 2575) $PN 180
J 2
(-1910 2585);
DISPLAY 0.680851 (-1910 2585);
PAINT MONO (-1910 2585);
FORCEPROP 0 LASTPIN (-1900 2625) $PN 182
J 2
(-1910 2635);
DISPLAY 0.680851 (-1910 2635);
PAINT MONO (-1910 2635);
FORCEPROP 0 LASTPIN (-1900 2675) $PN 184
J 2
(-1910 2685);
DISPLAY 0.680851 (-1910 2685);
PAINT MONO (-1910 2685);
FORCEPROP 0 LASTPIN (-1900 2725) $PN 186
J 2
(-1910 2735);
DISPLAY 0.680851 (-1910 2735);
PAINT MONO (-1910 2735);
FORCEPROP 0 LASTPIN (-1900 2775) $PN 188
J 2
(-1910 2785);
DISPLAY 0.680851 (-1910 2785);
PAINT MONO (-1910 2785);
FORCEPROP 0 LASTPIN (-1900 2825) $PN 191
J 2
(-1910 2835);
DISPLAY 0.680851 (-1910 2835);
PAINT MONO (-1910 2835);
FORCEPROP 0 LASTPIN (-1900 2875) $PN 193
J 2
(-1910 2885);
DISPLAY 0.680851 (-1910 2885);
PAINT MONO (-1910 2885);
FORCEPROP 0 LASTPIN (-1900 2925) $PN 195
J 2
(-1910 2935);
DISPLAY 0.680851 (-1910 2935);
PAINT MONO (-1910 2935);
FORCEPROP 0 LASTPIN (-1900 2975) $PN 197
J 2
(-1910 2985);
DISPLAY 0.680851 (-1910 2985);
PAINT MONO (-1910 2985);
FORCEPROP 0 LASTPIN (-1900 3025) $PN 199
J 2
(-1910 3035);
DISPLAY 0.680851 (-1910 3035);
PAINT MONO (-1910 3035);
FORCEPROP 0 LASTPIN (-1900 3075) $PN 202
J 2
(-1910 3085);
DISPLAY 0.680851 (-1910 3085);
PAINT MONO (-1910 3085);
FORCEPROP 0 LASTPIN (-1900 3125) $PN 204
J 2
(-1910 3135);
DISPLAY 0.680851 (-1910 3135);
PAINT MONO (-1910 3135);
FORCEPROP 0 LASTPIN (-1900 3175) $PN 206
J 2
(-1910 3185);
DISPLAY 0.680851 (-1910 3185);
PAINT MONO (-1910 3185);
FORCEPROP 0 LASTPIN (-1900 3225) $PN 208
J 2
(-1910 3235);
DISPLAY 0.680851 (-1910 3235);
PAINT MONO (-1910 3235);
FORCEPROP 0 LASTPIN (-1900 3275) $PN 210
J 2
(-1910 3285);
DISPLAY 0.680851 (-1910 3285);
PAINT MONO (-1910 3285);
FORCEPROP 0 LASTPIN (-1900 3325) $PN 212
J 2
(-1910 3335);
DISPLAY 0.680851 (-1910 3335);
PAINT MONO (-1910 3335);
FORCEPROP 0 LASTPIN (-1900 3375) $PN 214
J 2
(-1910 3385);
DISPLAY 0.680851 (-1910 3385);
PAINT MONO (-1910 3385);
FORCEPROP 0 LASTPIN (-1900 3425) $PN 216
J 2
(-1910 3435);
DISPLAY 0.680851 (-1910 3435);
PAINT MONO (-1910 3435);
FORCEPROP 0 LASTPIN (-1900 3475) $PN 219
J 2
(-1910 3485);
DISPLAY 0.680851 (-1910 3485);
PAINT MONO (-1910 3485);
FORCEPROP 0 LASTPIN (-1900 3525) $PN 222
J 2
(-1910 3535);
DISPLAY 0.680851 (-1910 3535);
PAINT MONO (-1910 3535);
FORCEPROP 0 LASTPIN (-1900 3575) $PN 224
J 2
(-1910 3585);
DISPLAY 0.680851 (-1910 3585);
PAINT MONO (-1910 3585);
FORCEPROP 0 LASTPIN (-1900 3625) $PN 226
J 2
(-1910 3635);
DISPLAY 0.680851 (-1910 3635);
PAINT MONO (-1910 3635);
FORCEPROP 0 LASTPIN (-1900 3675) $PN 228
J 2
(-1910 3685);
DISPLAY 0.680851 (-1910 3685);
PAINT MONO (-1910 3685);
FORCEPROP 0 LASTPIN (-1900 3725) $PN 230
J 2
(-1910 3735);
DISPLAY 0.680851 (-1910 3735);
PAINT MONO (-1910 3735);
FORCEPROP 0 LASTPIN (-1900 3775) $PN 233
J 2
(-1910 3785);
DISPLAY 0.680851 (-1910 3785);
PAINT MONO (-1910 3785);
FORCEPROP 0 LASTPIN (-1900 3825) $PN 235
J 2
(-1910 3835);
DISPLAY 0.680851 (-1910 3835);
PAINT MONO (-1910 3835);
FORCEPROP 0 LASTPIN (-1900 3875) $PN 237
J 2
(-1910 3885);
DISPLAY 0.680851 (-1910 3885);
PAINT MONO (-1910 3885);
FORCEPROP 0 LASTPIN (-1900 3925) $PN 240
J 2
(-1910 3935);
DISPLAY 0.680851 (-1910 3935);
PAINT MONO (-1910 3935);
FORCEPROP 0 LASTPIN (-1900 3975) $PN 242
J 2
(-1910 3985);
DISPLAY 0.680851 (-1910 3985);
PAINT MONO (-1910 3985);
FORCEPROP 0 LASTPIN (-1900 4025) $PN 244
J 2
(-1910 4035);
DISPLAY 0.680851 (-1910 4035);
PAINT MONO (-1910 4035);
FORCEPROP 0 LASTPIN (-1900 4075) $PN 246
J 2
(-1910 4085);
DISPLAY 0.680851 (-1910 4085);
PAINT MONO (-1910 4085);
FORCEPROP 0 LASTPIN (-1900 4125) $PN 248
J 2
(-1910 4135);
DISPLAY 0.680851 (-1910 4135);
PAINT MONO (-1910 4135);
FORCEPROP 0 LASTPIN (-1900 4175) $PN 251
J 2
(-1910 4185);
DISPLAY 0.680851 (-1910 4185);
PAINT MONO (-1910 4185);
FORCEPROP 0 LASTPIN (-1900 4225) $PN 253
J 2
(-1910 4235);
DISPLAY 0.680851 (-1910 4235);
PAINT MONO (-1910 4235);
FORCEPROP 0 LASTPIN (-1900 4275) $PN 255
J 2
(-1910 4285);
DISPLAY 0.680851 (-1910 4285);
PAINT MONO (-1910 4285);
FORCEPROP 0 LASTPIN (-1900 4325) $PN 257
J 2
(-1910 4335);
DISPLAY 0.680851 (-1910 4335);
PAINT MONO (-1910 4335);
FORCEPROP 0 LASTPIN (-1900 4375) $PN 259
J 2
(-1910 4385);
DISPLAY 0.680851 (-1910 4385);
PAINT MONO (-1910 4385);
FORCEPROP 0 LASTPIN (-1900 4425) $PN 262
J 2
(-1910 4435);
DISPLAY 0.680851 (-1910 4435);
PAINT MONO (-1910 4435);
FORCEPROP 0 LASTPIN (-1900 4475) $PN 264
J 2
(-1910 4485);
DISPLAY 0.680851 (-1910 4485);
PAINT MONO (-1910 4485);
FORCEPROP 0 LASTPIN (-1900 4525) $PN 266
J 2
(-1910 4535);
DISPLAY 0.680851 (-1910 4535);
PAINT MONO (-1910 4535);
FORCEPROP 0 LASTPIN (-1900 4575) $PN 268
J 2
(-1910 4585);
DISPLAY 0.680851 (-1910 4585);
PAINT MONO (-1910 4585);
FORCEPROP 0 LASTPIN (-1900 4625) $PN 270
J 2
(-1910 4635);
DISPLAY 0.680851 (-1910 4635);
PAINT MONO (-1910 4635);
FORCEPROP 0 LASTPIN (-1900 4675) $PN 273
J 2
(-1910 4685);
DISPLAY 0.680851 (-1910 4685);
PAINT MONO (-1910 4685);
FORCEPROP 0 LASTPIN (-1900 4725) $PN 275
J 2
(-1910 4735);
DISPLAY 0.680851 (-1910 4735);
PAINT MONO (-1910 4735);
FORCEPROP 0 LASTPIN (-1900 4775) $PN 277
J 2
(-1910 4785);
DISPLAY 0.680851 (-1910 4785);
PAINT MONO (-1910 4785);
FORCEPROP 0 LASTPIN (-1900 4825) $PN 279
J 2
(-1910 4835);
DISPLAY 0.680851 (-1910 4835);
PAINT MONO (-1910 4835);
FORCEPROP 0 LASTPIN (-1900 4875) $PN 281
J 2
(-1910 4885);
DISPLAY 0.680851 (-1910 4885);
PAINT MONO (-1910 4885);
FORCEPROP 0 LASTPIN (-1900 4925) $PN 284
J 2
(-1910 4935);
DISPLAY 0.680851 (-1910 4935);
PAINT MONO (-1910 4935);
FORCEPROP 0 LASTPIN (-1900 4975) $PN 286
J 2
(-1910 4985);
DISPLAY 0.680851 (-1910 4985);
PAINT MONO (-1910 4985);
FORCEPROP 0 LASTPIN (-1900 5025) $PN 288
J 2
(-1910 5035);
DISPLAY 0.680851 (-1910 5035);
PAINT MONO (-1910 5035);
FORCEPROP 2 LAST VALUE SCONN288_DDR506112002KQ
J 0
(-1750 5550);
DISPLAY 0.489362 (-1750 5550);
PAINT SKYBLUE (-1750 5550);
FORCEPROP 2 LAST PART_TYPE SMLF
J 0
(-1750 5600);
DISPLAY 1.021277 (-1750 5600);
FORCEPROP 1 LAST MATERIAL IO
J 0
(-1750 5350);
DISPLAY 0.468085 (-1750 5350);
PAINT SKYBLUE (-1750 5350);
FORCEPROP 1 LAST CDS_LMAN_SYM_OUTLINE -450,1800,450,-1750
J 0
(-1300 3525);
DISPLAY 0.468085 (-1300 3525);
PAINT GREEN (-1300 3525);
DISPLAY INVISIBLE (-1300 3525);
FORCEPROP 1 LAST NEEDS_NO_SIZE TRUE
J 0
(-1300 3525);
DISPLAY 0.723404 (-1300 3525);
PAINT GREEN (-1300 3525);
DISPLAY INVISIBLE (-1300 3525);
FORCEPROP 2 LAST CDS_LIB pure_quanta
J 0
(-1300 3525);
DISPLAY INVISIBLE (-1300 3525);
FORCEPROP 1 LAST PATH I140
J 0
(-1300 3525);
DISPLAY 0.723404 (-1300 3525);
PAINT GREEN (-1300 3525);
DISPLAY INVISIBLE (-1300 3525);
FORCEPROP 1 LAST PART_NUMBER DFHST8FS479
J 0
(-1750 5425);
DISPLAY 0.468085 (-1750 5425);
PAINT SKYBLUE (-1750 5425);
DISPLAY INVISIBLE (-1750 5425);
FORCEADD OFFPAGE..1
(-8325 3975);
FORCEPROP 2 LAST $XR0 21 
J 0
(-8546 3975);
DISPLAY 0.638298 (-8546 3975);
PAINT MONO (-8546 3975);
FORCEPROP 2 LAST CDS_LIB mstr_standard
J 0
(-8325 3975);
DISPLAY 0.723404 (-8325 3975);
PAINT MONO (-8325 3975);
DISPLAY INVISIBLE (-8325 3975);
FORCEPROP 1 LAST OFFPAGE TRUE
J 0
(-8000 3850);
DISPLAY 0.872340 (-8000 3850);
PAINT GREEN (-8000 3850);
DISPLAY INVISIBLE (-8000 3850);
FORCEPROP 1 LAST COMMENT_BODY TRUE
J 0
(-8200 3875);
DISPLAY 0.872340 (-8200 3875);
PAINT GREEN (-8200 3875);
DISPLAY INVISIBLE (-8200 3875);
FORCEPROP 2 LAST PATH I15
J 0
(-8275 4050);
DISPLAY 1.021277 (-8275 4050);
DISPLAY INVISIBLE (-8275 4050);
FORCEADD OFFPAGE..1
(-8325 4125);
FORCEPROP 2 LAST $XR0 21 
J 0
(-8546 4125);
DISPLAY 0.638298 (-8546 4125);
PAINT MONO (-8546 4125);
FORCEPROP 2 LAST CDS_LIB mstr_standard
J 0
(-8325 4125);
DISPLAY 0.723404 (-8325 4125);
PAINT MONO (-8325 4125);
DISPLAY INVISIBLE (-8325 4125);
FORCEPROP 1 LAST OFFPAGE TRUE
J 0
(-8000 4000);
DISPLAY 0.872340 (-8000 4000);
PAINT GREEN (-8000 4000);
DISPLAY INVISIBLE (-8000 4000);
FORCEPROP 1 LAST COMMENT_BODY TRUE
J 0
(-8200 4025);
DISPLAY 0.872340 (-8200 4025);
PAINT GREEN (-8200 4025);
DISPLAY INVISIBLE (-8200 4025);
FORCEPROP 2 LAST PATH I16
J 0
(-8275 4200);
DISPLAY 1.021277 (-8275 4200);
DISPLAY INVISIBLE (-8275 4200);
FORCEADD OFFPAGE..1
(-8325 4075);
FORCEPROP 2 LAST $XR0 21 
J 0
(-8546 4075);
DISPLAY 0.638298 (-8546 4075);
PAINT MONO (-8546 4075);
FORCEPROP 2 LAST CDS_LIB mstr_standard
J 0
(-8325 4075);
DISPLAY 0.808511 (-8325 4075);
DISPLAY INVISIBLE (-8325 4075);
FORCEPROP 1 LAST OFFPAGE TRUE
J 0
(-8000 3950);
DISPLAY 0.872340 (-8000 3950);
PAINT GREEN (-8000 3950);
DISPLAY INVISIBLE (-8000 3950);
FORCEPROP 1 LAST COMMENT_BODY TRUE
J 0
(-8200 3975);
DISPLAY 0.872340 (-8200 3975);
PAINT GREEN (-8200 3975);
DISPLAY INVISIBLE (-8200 3975);
FORCEPROP 2 LAST PATH I17
J 0
(-8275 4150);
DISPLAY 1.021277 (-8275 4150);
DISPLAY INVISIBLE (-8275 4150);
FORCEADD OFFPAGE..1
(-8325 4275);
FORCEPROP 2 LAST $XR0 21 
J 0
(-8546 4275);
DISPLAY 0.638298 (-8546 4275);
PAINT MONO (-8546 4275);
FORCEPROP 2 LAST CDS_LIB mstr_standard
J 0
(-8325 4275);
DISPLAY 0.723404 (-8325 4275);
PAINT MONO (-8325 4275);
DISPLAY INVISIBLE (-8325 4275);
FORCEPROP 1 LAST OFFPAGE TRUE
J 0
(-8000 4150);
DISPLAY 0.872340 (-8000 4150);
PAINT GREEN (-8000 4150);
DISPLAY INVISIBLE (-8000 4150);
FORCEPROP 1 LAST COMMENT_BODY TRUE
J 0
(-8200 4175);
DISPLAY 0.872340 (-8200 4175);
PAINT GREEN (-8200 4175);
DISPLAY INVISIBLE (-8200 4175);
FORCEPROP 2 LAST PATH I18
J 0
(-8275 4350);
DISPLAY 1.021277 (-8275 4350);
DISPLAY INVISIBLE (-8275 4350);
FORCEADD Q_CAP..1
R 2
(-8600 2900);
FORCEPROP 1 LAST LOCATION C132
J 2
(-8650 3000);
DISPLAY 0.489362 (-8650 3000);
PAINT SKYBLUE (-8650 3000);
FORCEPROP 0 LAST $SEC 1
J 0
(-8650 3050);
DISPLAY 0.680851 (-8650 3050);
PAINT MONO (-8650 3050);
DISPLAY INVISIBLE (-8650 3050);
FORCEPROP 0 LAST CDS_SEC 1
J 0
(-8650 3050);
DISPLAY 1.021277 (-8650 3050);
DISPLAY INVISIBLE (-8650 3050);
FORCEPROP 1 LASTPIN (-8600 3000) $PN 1
J 2
(-8610 2980);
DISPLAY 0.489362 (-8610 2980);
PAINT MONO (-8610 2980);
FORCEPROP 1 LASTPIN (-8600 2800) $PN 2
J 2
(-8610 2780);
DISPLAY 0.489362 (-8610 2780);
PAINT MONO (-8610 2780);
FORCEPROP 1 LAST PACK_TYPE 0402
J 2
(-8650 2700);
DISPLAY 0.489362 (-8650 2700);
PAINT SKYBLUE (-8650 2700);
FORCEPROP 1 LAST VOLTAGE 25V
J 2
(-8650 2900);
DISPLAY 0.489362 (-8650 2900);
PAINT SKYBLUE (-8650 2900);
FORCEPROP 1 LAST TOLERANCE 10%
J 2
(-8650 2850);
DISPLAY 0.489362 (-8650 2850);
PAINT SKYBLUE (-8650 2850);
FORCEPROP 1 LAST VALUE 0.1UF
J 2
(-8650 2950);
DISPLAY 0.489362 (-8650 2950);
PAINT SKYBLUE (-8650 2950);
FORCEPROP 1 LAST MATERIAL X7R
J 2
(-8650 2800);
DISPLAY 0.489362 (-8650 2800);
PAINT SKYBLUE (-8650 2800);
FORCEPROP 0 LAST BOM_COST MEM
J 2
(-8655 3045);
DISPLAY 0.595745 (-8655 3045);
PAINT MONO (-8655 3045);
DISPLAY INVISIBLE (-8655 3045);
FORCEPROP 2 LAST CDS_LIB pure_quanta
J 0
(-8600 2900);
DISPLAY INVISIBLE (-8600 2900);
FORCEPROP 2 LAST ROOM 
J 2
(-8655 3045);
DISPLAY 0.595745 (-8655 3045);
PAINT RED (-8655 3045);
DISPLAY INVISIBLE (-8655 3045);
FORCEPROP 1 LAST PATH I185
J 2
(-8650 3050);
DISPLAY 0.978723 (-8650 3050);
PAINT WHITE (-8650 3050);
DISPLAY INVISIBLE (-8650 3050);
FORCEPROP 1 LAST PART_NUMBER CH4104K1B00
J 2
(-8650 2750);
DISPLAY 0.489362 (-8650 2750);
PAINT SKYBLUE (-8650 2750);
DISPLAY INVISIBLE (-8650 2750);
FORCEADD GND..1
(-8600 2675);
FORCEPROP 3 LASTPIN (-8600 2725) SIG_NAME GND\g
J 0
(-8590 2735);
DISPLAY 0.659574 (-8590 2735);
PAINT MONO (-8590 2735);
DISPLAY INVISIBLE (-8590 2735);
FORCEPROP 2 LAST CDS_LIB mstr_symbols
J 0
(-8600 2675);
DISPLAY 0.808511 (-8600 2675);
DISPLAY INVISIBLE (-8600 2675);
FORCEPROP 1 LAST SIZE 1B
J 0
(-8525 2625);
DISPLAY 0.723404 (-8525 2625);
PAINT GREEN (-8525 2625);
DISPLAY INVISIBLE (-8525 2625);
FORCEPROP 2 LAST BOM_COST MEM
J 0
(-8575 2800);
DISPLAY 0.659574 (-8575 2800);
DISPLAY INVISIBLE (-8575 2800);
FORCEPROP 1 LAST VOLTAGE 0
J 0
(-8620 2770);
DISPLAY 0.829787 (-8620 2770);
PAINT SKYBLUE (-8620 2770);
DISPLAY INVISIBLE (-8620 2770);
FORCEPROP 2 LAST ROOM MEM_EFGH_DECOUPLING_CAPS
J 0
(-8575 2750);
DISPLAY 0.659574 (-8575 2750);
PAINT RED (-8575 2750);
DISPLAY INVISIBLE (-8575 2750);
FORCEPROP 1 LAST BODY_TYPE PLUMBING
J 0
(-8645 2632);
DISPLAY 0.276596 (-8645 2632);
PAINT GREEN (-8645 2632);
DISPLAY INVISIBLE (-8645 2632);
FORCEPROP 1 LAST HDL_POWER GND
J 0
(-8600 2825);
DISPLAY 0.723404 (-8600 2825);
PAINT GREEN (-8600 2825);
DISPLAY INVISIBLE (-8600 2825);
FORCEPROP 1 LAST PATH I186
J 0
(-8525 2675);
DISPLAY 0.872340 (-8525 2675);
PAINT AQUA (-8525 2675);
DISPLAY INVISIBLE (-8525 2675);
FORCEADD OFFPAGE..6
(-9000 1825);
FORCEPROP 2 LAST $XR4 96 
J 0
(-9339 1789);
DISPLAY 0.638298 (-9339 1789);
PAINT MONO (-9339 1789);
FORCEPROP 2 LAST $XR3 95 
J 0
(-9249 1789);
DISPLAY 0.638298 (-9249 1789);
PAINT MONO (-9249 1789);
FORCEPROP 2 LAST $XR2 94 
J 0
(-9429 1825);
DISPLAY 0.638298 (-9429 1825);
PAINT MONO (-9429 1825);
FORCEPROP 2 LAST $XR1 93 
J 0
(-9339 1825);
DISPLAY 0.638298 (-9339 1825);
PAINT MONO (-9339 1825);
FORCEPROP 2 LAST $XR0 92 
J 0
(-9249 1825);
DISPLAY 0.638298 (-9249 1825);
PAINT MONO (-9249 1825);
FORCEPROP 2 LAST CDS_LIB mstr_standard
J 0
(-9000 1825);
DISPLAY INVISIBLE (-9000 1825);
FORCEPROP 1 LAST OFFPAGE TRUE
J 0
(-8675 1700);
DISPLAY 0.872340 (-8675 1700);
PAINT GREEN (-8675 1700);
DISPLAY INVISIBLE (-8675 1700);
FORCEPROP 1 LAST COMMENT_BODY TRUE
J 0
(-8900 1750);
DISPLAY 0.872340 (-8900 1750);
PAINT GREEN (-8900 1750);
DISPLAY INVISIBLE (-8900 1750);
FORCEPROP 2 LAST PATH I187
J 0
(-8950 1900);
DISPLAY 1.021277 (-8950 1900);
DISPLAY INVISIBLE (-8950 1900);
FORCEADD Q_RES..1
R 2
(-8475 1825);
FORCEPROP 1 LAST LOCATION R302
J 2
(-8425 1875);
DISPLAY 0.489362 (-8425 1875);
PAINT SKYBLUE (-8425 1875);
FORCEPROP 0 LAST $SEC 1
J 0
(-8425 1925);
DISPLAY 0.680851 (-8425 1925);
PAINT MONO (-8425 1925);
DISPLAY INVISIBLE (-8425 1925);
FORCEPROP 0 LAST CDS_SEC 1
J 0
(-8425 1925);
DISPLAY 1.021277 (-8425 1925);
DISPLAY INVISIBLE (-8425 1925);
FORCEPROP 1 LASTPIN (-8375 1825) $PN 1
J 2
(-8387 1837);
DISPLAY 0.489362 (-8387 1837);
PAINT MONO (-8387 1837);
FORCEPROP 1 LASTPIN (-8575 1825) $PN 2
J 2
(-8537 1837);
DISPLAY 0.489362 (-8537 1837);
PAINT MONO (-8537 1837);
FORCEPROP 1 LAST VALUE 1K
J 0
(-8475 1775);
DISPLAY 0.489362 (-8475 1775);
PAINT SKYBLUE (-8475 1775);
FORCEPROP 1 LAST TOLERANCE 1%
J 2
(-8350 1800);
DISPLAY 0.489362 (-8350 1800);
PAINT SKYBLUE (-8350 1800);
DISPLAY INVISIBLE (-8350 1800);
FORCEPROP 2 LAST CDS_LIB pure_quanta
J 0
(-8475 1825);
DISPLAY INVISIBLE (-8475 1825);
FORCEPROP 2 LAST BOM_COST MEM
J 0
(-8500 1975);
DISPLAY 0.744681 (-8500 1975);
PAINT WHITE (-8500 1975);
DISPLAY INVISIBLE (-8500 1975);
FORCEPROP 1 LAST WATTAGE 1/16W
J 0
(-8400 1750);
DISPLAY 0.489362 (-8400 1750);
PAINT SKYBLUE (-8400 1750);
DISPLAY INVISIBLE (-8400 1750);
FORCEPROP 1 LAST MATERIAL CHIP
J 0
(-8650 1800);
DISPLAY 0.489362 (-8650 1800);
PAINT SKYBLUE (-8650 1800);
DISPLAY INVISIBLE (-8650 1800);
FORCEPROP 1 LAST PACK_TYPE 0402LF
J 0
(-8650 1750);
DISPLAY 0.489362 (-8650 1750);
PAINT SKYBLUE (-8650 1750);
DISPLAY INVISIBLE (-8650 1750);
FORCEPROP 2 LAST ROOM 
J 0
(-8500 1925);
DISPLAY 0.744681 (-8500 1925);
PAINT RED (-8500 1925);
DISPLAY INVISIBLE (-8500 1925);
FORCEPROP 1 LAST PATH I188
J 2
(-8425 1975);
DISPLAY 0.978723 (-8425 1975);
PAINT WHITE (-8425 1975);
DISPLAY INVISIBLE (-8425 1975);
FORCEPROP 1 LAST PART_NUMBER CS21002FB06
J 0
(-8575 1875);
DISPLAY 0.489362 (-8575 1875);
PAINT SKYBLUE (-8575 1875);
DISPLAY INVISIBLE (-8575 1875);
FORCEADD Q_RES..2
(-8350 1975);
FORCEPROP 1 LAST LOCATION R101
J 0
(-8305 2100);
DISPLAY 0.489362 (-8305 2100);
PAINT SKYBLUE (-8305 2100);
FORCEPROP 0 LAST $SEC 1
J 0
(-8300 2150);
DISPLAY 0.680851 (-8300 2150);
PAINT MONO (-8300 2150);
DISPLAY INVISIBLE (-8300 2150);
FORCEPROP 0 LAST CDS_SEC 1
J 0
(-8300 2150);
DISPLAY 1.021277 (-8300 2150);
DISPLAY INVISIBLE (-8300 2150);
FORCEPROP 1 LASTPIN (-8350 2075) $PN 1
J 0
(-8345 2037);
DISPLAY 0.489362 (-8345 2037);
PAINT MONO (-8345 2037);
FORCEPROP 1 LASTPIN (-8350 1875) $PN 2
J 0
(-8345 1885);
DISPLAY 0.489362 (-8345 1885);
PAINT MONO (-8345 1885);
FORCEPROP 1 LAST TOLERANCE 1%
J 0
(-8300 2025);
DISPLAY 0.489362 (-8300 2025);
PAINT SKYBLUE (-8300 2025);
FORCEPROP 1 LAST WATTAGE 1/16W
J 0
(-8300 2000);
DISPLAY 0.489362 (-8300 2000);
PAINT SKYBLUE (-8300 2000);
FORCEPROP 1 LAST MATERIAL EMPTY
J 0
(-8300 1975);
DISPLAY 0.489362 (-8300 1975);
PAINT RED (-8300 1975);
FORCEPROP 1 LAST PACK_TYPE 0402LF
J 0
(-8300 1925);
DISPLAY 0.489362 (-8300 1925);
PAINT SKYBLUE (-8300 1925);
FORCEPROP 1 LAST VALUE 1K
J 0
(-8305 2050);
DISPLAY 0.489362 (-8305 2050);
PAINT SKYBLUE (-8305 2050);
FORCEPROP 2 LAST CDS_LIB pure_quanta
J 0
(-8350 1975);
DISPLAY INVISIBLE (-8350 1975);
FORCEPROP 2 LAST BOM_COST MEM
J 0
(-8300 2150);
DISPLAY 0.808511 (-8300 2150);
DISPLAY INVISIBLE (-8300 2150);
FORCEPROP 2 LAST ROOM 
J 0
(-8300 2200);
DISPLAY 0.808511 (-8300 2200);
PAINT RED (-8300 2200);
DISPLAY INVISIBLE (-8300 2200);
FORCEPROP 1 LAST PATH I189
J 0
(-8300 2150);
DISPLAY 0.978723 (-8300 2150);
PAINT WHITE (-8300 2150);
DISPLAY INVISIBLE (-8300 2150);
FORCEPROP 1 LAST PART_NUMBER CS21002FB06
J 0
(-8300 1950);
DISPLAY 0.489362 (-8300 1950);
PAINT SKYBLUE (-8300 1950);
DISPLAY INVISIBLE (-8300 1950);
FORCEADD OFFPAGE..1
(-8325 4225);
FORCEPROP 2 LAST $XR0 21 
J 0
(-8546 4225);
DISPLAY 0.638298 (-8546 4225);
PAINT MONO (-8546 4225);
FORCEPROP 2 LAST CDS_LIB mstr_standard
J 0
(-8325 4225);
DISPLAY 0.808511 (-8325 4225);
DISPLAY INVISIBLE (-8325 4225);
FORCEPROP 1 LAST OFFPAGE TRUE
J 0
(-8000 4100);
DISPLAY 0.872340 (-8000 4100);
PAINT GREEN (-8000 4100);
DISPLAY INVISIBLE (-8000 4100);
FORCEPROP 1 LAST COMMENT_BODY TRUE
J 0
(-8200 4125);
DISPLAY 0.872340 (-8200 4125);
PAINT GREEN (-8200 4125);
DISPLAY INVISIBLE (-8200 4125);
FORCEPROP 2 LAST PATH I19
J 0
(-8275 4300);
DISPLAY 1.021277 (-8275 4300);
DISPLAY INVISIBLE (-8275 4300);
FORCEADD VCC_CORE..1
(-8350 2150);
FORCEPROP 3 LASTPIN (-8350 2100) SIG_NAME P3V3\g
J 0
(-8340 2110);
DISPLAY 0.659574 (-8340 2110);
PAINT MONO (-8340 2110);
DISPLAY INVISIBLE (-8340 2110);
FORCEPROP 1 LAST HDL_POWER P3V3
J 1
(-8350 2200);
DISPLAY 0.489362 (-8350 2200);
PAINT GREEN (-8350 2200);
FORCEPROP 2 LAST CDS_LIB mstr_symbols
J 0
(-8350 2150);
DISPLAY INVISIBLE (-8350 2150);
FORCEPROP 0 LAST VOLTAGE 3.3
J 0
(-8625 2300);
DISPLAY 1.021277 (-8625 2300);
PAINT SKYBLUE (-8625 2300);
DISPLAY INVISIBLE (-8625 2300);
FORCEPROP 2 LAST ROOM PVCCINFAON_CPU0_CTRL
J 0
(-8350 2250);
DISPLAY 0.808511 (-8350 2250);
PAINT RED (-8350 2250);
DISPLAY INVISIBLE (-8350 2250);
FORCEPROP 1 LAST PATH I190
J 0
(-8300 2175);
DISPLAY 0.872340 (-8300 2175);
PAINT AQUA (-8300 2175);
DISPLAY INVISIBLE (-8300 2175);
FORCEADD OFFPAGE..2
(-2500 4350);
FORCEPROP 2 LAST $XR0 21 
J 0
(-2311 4350);
DISPLAY 0.638298 (-2311 4350);
PAINT MONO (-2311 4350);
FORCEPROP 2 LAST CDS_LIB mstr_standard
J 0
(-2500 4350);
DISPLAY 0.723404 (-2500 4350);
PAINT MONO (-2500 4350);
DISPLAY INVISIBLE (-2500 4350);
FORCEPROP 1 LAST OFFPAGE TRUE
J 0
(-2175 4225);
DISPLAY 0.723404 (-2175 4225);
PAINT GREEN (-2175 4225);
DISPLAY INVISIBLE (-2175 4225);
FORCEPROP 1 LAST COMMENT_BODY TRUE
J 0
(-2545 4255);
DISPLAY 0.872340 (-2545 4255);
PAINT GREEN (-2545 4255);
DISPLAY INVISIBLE (-2545 4255);
FORCEPROP 2 LAST PATH I192
J 0
(-2300 4400);
DISPLAY 0.680851 (-2300 4400);
DISPLAY INVISIBLE (-2300 4400);
FORCEADD OFFPAGE..2
(-2500 4300);
FORCEPROP 2 LAST $XR0 21 
J 0
(-2311 4300);
DISPLAY 0.638298 (-2311 4300);
PAINT MONO (-2311 4300);
FORCEPROP 2 LAST CDS_LIB mstr_standard
J 0
(-2500 4300);
DISPLAY 0.723404 (-2500 4300);
PAINT MONO (-2500 4300);
DISPLAY INVISIBLE (-2500 4300);
FORCEPROP 1 LAST OFFPAGE TRUE
J 0
(-2175 4175);
DISPLAY 0.723404 (-2175 4175);
PAINT GREEN (-2175 4175);
DISPLAY INVISIBLE (-2175 4175);
FORCEPROP 1 LAST COMMENT_BODY TRUE
J 0
(-2545 4205);
DISPLAY 0.872340 (-2545 4205);
PAINT GREEN (-2545 4205);
DISPLAY INVISIBLE (-2545 4205);
FORCEPROP 2 LAST PATH I193
J 0
(-2300 4350);
DISPLAY 0.680851 (-2300 4350);
DISPLAY INVISIBLE (-2300 4350);
FORCEADD TAP..1
(-3300 4250);
FORCEPROP 3 LASTPIN (-3350 4250) SIG_NAME M_L_CPU0_SA_DQS_DN<9>
J 0
(-3340 4260);
DISPLAY 0.659574 (-3340 4260);
PAINT MONO (-3340 4260);
DISPLAY INVISIBLE (-3340 4260);
FORCEPROP 1 LASTPIN (-3350 4250) BN 9
J 0
(-3362 4258);
DISPLAY 0.489362 (-3362 4258);
PAINT GREEN (-3362 4258);
FORCEPROP 2 LAST CDS_LIB mstr_standard
J 0
(-3300 4250);
DISPLAY 0.723404 (-3300 4250);
PAINT MONO (-3300 4250);
DISPLAY INVISIBLE (-3300 4250);
FORCEPROP 1 LAST BODY_TYPE PLUMBING
J 0
(-3300 4300);
DISPLAY 0.872340 (-3300 4300);
PAINT GREEN (-3300 4300);
DISPLAY INVISIBLE (-3300 4300);
FORCEPROP 1 LAST HDL_TAP TRUE
J 0
(-2975 4125);
DISPLAY 0.872340 (-2975 4125);
DISPLAY INVISIBLE (-2975 4125);
FORCEPROP 1 LAST PATH I194
J 0
(-3302 4250);
DISPLAY 0.872340 (-3302 4250);
PAINT GREEN (-3302 4250);
DISPLAY INVISIBLE (-3302 4250);
FORCEADD TAP..1
(-3500 4200);
FORCEPROP 3 LASTPIN (-3550 4200) SIG_NAME M_L_CPU0_SA_DQS_DP<8>
J 0
(-3540 4210);
DISPLAY 0.659574 (-3540 4210);
PAINT MONO (-3540 4210);
DISPLAY INVISIBLE (-3540 4210);
FORCEPROP 1 LASTPIN (-3550 4200) BN 8
J 0
(-3562 4208);
DISPLAY 0.489362 (-3562 4208);
PAINT GREEN (-3562 4208);
FORCEPROP 2 LAST CDS_LIB mstr_standard
J 0
(-3500 4200);
DISPLAY 0.723404 (-3500 4200);
PAINT MONO (-3500 4200);
DISPLAY INVISIBLE (-3500 4200);
FORCEPROP 1 LAST BODY_TYPE PLUMBING
J 0
(-3500 4250);
DISPLAY 0.872340 (-3500 4250);
PAINT GREEN (-3500 4250);
DISPLAY INVISIBLE (-3500 4250);
FORCEPROP 1 LAST HDL_TAP TRUE
J 0
(-3175 4075);
DISPLAY 0.872340 (-3175 4075);
DISPLAY INVISIBLE (-3175 4075);
FORCEPROP 1 LAST PATH I195
J 0
(-3502 4200);
DISPLAY 0.872340 (-3502 4200);
PAINT GREEN (-3502 4200);
DISPLAY INVISIBLE (-3502 4200);
FORCEADD TAP..1
(-3500 4300);
FORCEPROP 3 LASTPIN (-3550 4300) SIG_NAME M_L_CPU0_SA_DQS_DP<9>
J 0
(-3540 4310);
DISPLAY 0.659574 (-3540 4310);
PAINT MONO (-3540 4310);
DISPLAY INVISIBLE (-3540 4310);
FORCEPROP 1 LASTPIN (-3550 4300) BN 9
J 0
(-3562 4308);
DISPLAY 0.489362 (-3562 4308);
PAINT GREEN (-3562 4308);
FORCEPROP 2 LAST CDS_LIB mstr_standard
J 0
(-3500 4300);
DISPLAY 0.723404 (-3500 4300);
PAINT MONO (-3500 4300);
DISPLAY INVISIBLE (-3500 4300);
FORCEPROP 1 LAST BODY_TYPE PLUMBING
J 0
(-3500 4350);
DISPLAY 0.872340 (-3500 4350);
PAINT GREEN (-3500 4350);
DISPLAY INVISIBLE (-3500 4350);
FORCEPROP 1 LAST HDL_TAP TRUE
J 0
(-3175 4175);
DISPLAY 0.872340 (-3175 4175);
DISPLAY INVISIBLE (-3175 4175);
FORCEPROP 1 LAST PATH I196
J 0
(-3502 4300);
DISPLAY 0.872340 (-3502 4300);
PAINT GREEN (-3502 4300);
DISPLAY INVISIBLE (-3502 4300);
FORCEADD TAP..1
(-3300 4150);
FORCEPROP 3 LASTPIN (-3350 4150) SIG_NAME M_L_CPU0_SA_DQS_DN<8>
J 0
(-3340 4160);
DISPLAY 0.659574 (-3340 4160);
PAINT MONO (-3340 4160);
DISPLAY INVISIBLE (-3340 4160);
FORCEPROP 1 LASTPIN (-3350 4150) BN 8
J 0
(-3362 4158);
DISPLAY 0.489362 (-3362 4158);
PAINT GREEN (-3362 4158);
FORCEPROP 2 LAST CDS_LIB mstr_standard
J 0
(-3300 4150);
DISPLAY 0.723404 (-3300 4150);
PAINT MONO (-3300 4150);
DISPLAY INVISIBLE (-3300 4150);
FORCEPROP 1 LAST BODY_TYPE PLUMBING
J 0
(-3300 4200);
DISPLAY 0.872340 (-3300 4200);
PAINT GREEN (-3300 4200);
DISPLAY INVISIBLE (-3300 4200);
FORCEPROP 1 LAST HDL_TAP TRUE
J 0
(-2975 4025);
DISPLAY 0.872340 (-2975 4025);
DISPLAY INVISIBLE (-2975 4025);
FORCEPROP 1 LAST PATH I197
J 0
(-3302 4150);
DISPLAY 0.872340 (-3302 4150);
PAINT GREEN (-3302 4150);
DISPLAY INVISIBLE (-3302 4150);
FORCEADD TAP..1
(-3300 4050);
FORCEPROP 3 LASTPIN (-3350 4050) SIG_NAME M_L_CPU0_SA_DQS_DN<7>
J 0
(-3340 4060);
DISPLAY 0.659574 (-3340 4060);
PAINT MONO (-3340 4060);
DISPLAY INVISIBLE (-3340 4060);
FORCEPROP 1 LASTPIN (-3350 4050) BN 7
J 0
(-3362 4058);
DISPLAY 0.489362 (-3362 4058);
PAINT GREEN (-3362 4058);
FORCEPROP 2 LAST CDS_LIB mstr_standard
J 0
(-3300 4050);
DISPLAY 0.723404 (-3300 4050);
PAINT MONO (-3300 4050);
DISPLAY INVISIBLE (-3300 4050);
FORCEPROP 1 LAST BODY_TYPE PLUMBING
J 0
(-3300 4100);
DISPLAY 0.872340 (-3300 4100);
PAINT GREEN (-3300 4100);
DISPLAY INVISIBLE (-3300 4100);
FORCEPROP 1 LAST HDL_TAP TRUE
J 0
(-2975 3925);
DISPLAY 0.872340 (-2975 3925);
DISPLAY INVISIBLE (-2975 3925);
FORCEPROP 1 LAST PATH I198
J 0
(-3302 4050);
DISPLAY 0.872340 (-3302 4050);
PAINT GREEN (-3302 4050);
DISPLAY INVISIBLE (-3302 4050);
FORCEADD TAP..1
(-3300 3950);
FORCEPROP 3 LASTPIN (-3350 3950) SIG_NAME M_L_CPU0_SA_DQS_DN<6>
J 0
(-3340 3960);
DISPLAY 0.659574 (-3340 3960);
PAINT MONO (-3340 3960);
DISPLAY INVISIBLE (-3340 3960);
FORCEPROP 1 LASTPIN (-3350 3950) BN 6
J 0
(-3362 3958);
DISPLAY 0.489362 (-3362 3958);
PAINT GREEN (-3362 3958);
FORCEPROP 2 LAST CDS_LIB mstr_standard
J 0
(-3300 3950);
DISPLAY 0.723404 (-3300 3950);
PAINT MONO (-3300 3950);
DISPLAY INVISIBLE (-3300 3950);
FORCEPROP 1 LAST BODY_TYPE PLUMBING
J 0
(-3300 4000);
DISPLAY 0.872340 (-3300 4000);
PAINT GREEN (-3300 4000);
DISPLAY INVISIBLE (-3300 4000);
FORCEPROP 1 LAST HDL_TAP TRUE
J 0
(-2975 3825);
DISPLAY 0.872340 (-2975 3825);
DISPLAY INVISIBLE (-2975 3825);
FORCEPROP 1 LAST PATH I199
J 0
(-3302 3950);
DISPLAY 0.872340 (-3302 3950);
PAINT GREEN (-3302 3950);
DISPLAY INVISIBLE (-3302 3950);
FORCEADD OFFPAGE..5
(-8325 1675);
FORCEPROP 2 LAST $XR0 21 
J 0
(-8549 1675);
DISPLAY 0.638298 (-8549 1675);
PAINT MONO (-8549 1675);
FORCEPROP 2 LAST CDS_LIB mstr_standard
J 0
(-8325 1675);
DISPLAY 0.808511 (-8325 1675);
DISPLAY INVISIBLE (-8325 1675);
FORCEPROP 1 LAST OFFPAGE TRUE
J 0
(-8000 1550);
DISPLAY 0.872340 (-8000 1550);
PAINT GREEN (-8000 1550);
DISPLAY INVISIBLE (-8000 1550);
FORCEPROP 1 LAST COMMENT_BODY TRUE
J 0
(-8225 1600);
DISPLAY 0.872340 (-8225 1600);
PAINT GREEN (-8225 1600);
DISPLAY INVISIBLE (-8225 1600);
FORCEPROP 2 LAST PATH I2
J 0
(-8275 1750);
DISPLAY 1.021277 (-8275 1750);
DISPLAY INVISIBLE (-8275 1750);
FORCEADD OFFPAGE..1
(-8325 5125);
FORCEPROP 2 LAST $XR0 21 
J 0
(-8546 5125);
DISPLAY 0.638298 (-8546 5125);
PAINT MONO (-8546 5125);
FORCEPROP 2 LAST CDS_LIB mstr_standard
J 0
(-8325 5125);
DISPLAY 0.723404 (-8325 5125);
PAINT MONO (-8325 5125);
DISPLAY INVISIBLE (-8325 5125);
FORCEPROP 1 LAST OFFPAGE TRUE
J 0
(-8000 5000);
DISPLAY 0.872340 (-8000 5000);
PAINT GREEN (-8000 5000);
DISPLAY INVISIBLE (-8000 5000);
FORCEPROP 1 LAST COMMENT_BODY TRUE
J 0
(-8200 5025);
DISPLAY 0.872340 (-8200 5025);
PAINT GREEN (-8200 5025);
DISPLAY INVISIBLE (-8200 5025);
FORCEPROP 2 LAST PATH I20
J 0
(-8275 5200);
DISPLAY 1.021277 (-8275 5200);
DISPLAY INVISIBLE (-8275 5200);
FORCEADD TAP..1
(-3500 4100);
FORCEPROP 3 LASTPIN (-3550 4100) SIG_NAME M_L_CPU0_SA_DQS_DP<7>
J 0
(-3540 4110);
DISPLAY 0.659574 (-3540 4110);
PAINT MONO (-3540 4110);
DISPLAY INVISIBLE (-3540 4110);
FORCEPROP 1 LASTPIN (-3550 4100) BN 7
J 0
(-3562 4108);
DISPLAY 0.489362 (-3562 4108);
PAINT GREEN (-3562 4108);
FORCEPROP 2 LAST CDS_LIB mstr_standard
J 0
(-3500 4100);
DISPLAY 0.723404 (-3500 4100);
PAINT MONO (-3500 4100);
DISPLAY INVISIBLE (-3500 4100);
FORCEPROP 1 LAST BODY_TYPE PLUMBING
J 0
(-3500 4150);
DISPLAY 0.872340 (-3500 4150);
PAINT GREEN (-3500 4150);
DISPLAY INVISIBLE (-3500 4150);
FORCEPROP 1 LAST HDL_TAP TRUE
J 0
(-3175 3975);
DISPLAY 0.872340 (-3175 3975);
DISPLAY INVISIBLE (-3175 3975);
FORCEPROP 1 LAST PATH I200
J 0
(-3502 4100);
DISPLAY 0.872340 (-3502 4100);
PAINT GREEN (-3502 4100);
DISPLAY INVISIBLE (-3502 4100);
FORCEADD TAP..1
(-3500 4000);
FORCEPROP 3 LASTPIN (-3550 4000) SIG_NAME M_L_CPU0_SA_DQS_DP<6>
J 0
(-3540 4010);
DISPLAY 0.659574 (-3540 4010);
PAINT MONO (-3540 4010);
DISPLAY INVISIBLE (-3540 4010);
FORCEPROP 1 LASTPIN (-3550 4000) BN 6
J 0
(-3562 4008);
DISPLAY 0.489362 (-3562 4008);
PAINT GREEN (-3562 4008);
FORCEPROP 2 LAST CDS_LIB mstr_standard
J 0
(-3500 4000);
DISPLAY 0.723404 (-3500 4000);
PAINT MONO (-3500 4000);
DISPLAY INVISIBLE (-3500 4000);
FORCEPROP 1 LAST BODY_TYPE PLUMBING
J 0
(-3500 4050);
DISPLAY 0.872340 (-3500 4050);
PAINT GREEN (-3500 4050);
DISPLAY INVISIBLE (-3500 4050);
FORCEPROP 1 LAST HDL_TAP TRUE
J 0
(-3175 3875);
DISPLAY 0.872340 (-3175 3875);
DISPLAY INVISIBLE (-3175 3875);
FORCEPROP 1 LAST PATH I201
J 0
(-3502 4000);
DISPLAY 0.872340 (-3502 4000);
PAINT GREEN (-3502 4000);
DISPLAY INVISIBLE (-3502 4000);
FORCEADD TAP..1
(-3300 3750);
FORCEPROP 3 LASTPIN (-3350 3750) SIG_NAME M_L_CPU0_SA_DQS_DN<4>
J 0
(-3340 3760);
DISPLAY 0.659574 (-3340 3760);
PAINT MONO (-3340 3760);
DISPLAY INVISIBLE (-3340 3760);
FORCEPROP 1 LASTPIN (-3350 3750) BN 4
J 0
(-3362 3758);
DISPLAY 0.489362 (-3362 3758);
PAINT GREEN (-3362 3758);
FORCEPROP 2 LAST CDS_LIB mstr_standard
J 0
(-3300 3750);
DISPLAY 0.723404 (-3300 3750);
PAINT MONO (-3300 3750);
DISPLAY INVISIBLE (-3300 3750);
FORCEPROP 1 LAST BODY_TYPE PLUMBING
J 0
(-3300 3800);
DISPLAY 0.872340 (-3300 3800);
PAINT GREEN (-3300 3800);
DISPLAY INVISIBLE (-3300 3800);
FORCEPROP 1 LAST HDL_TAP TRUE
J 0
(-2975 3625);
DISPLAY 0.872340 (-2975 3625);
DISPLAY INVISIBLE (-2975 3625);
FORCEPROP 1 LAST PATH I202
J 0
(-3302 3750);
DISPLAY 0.872340 (-3302 3750);
PAINT GREEN (-3302 3750);
DISPLAY INVISIBLE (-3302 3750);
FORCEADD TAP..1
(-3300 3850);
FORCEPROP 3 LASTPIN (-3350 3850) SIG_NAME M_L_CPU0_SA_DQS_DN<5>
J 0
(-3340 3860);
DISPLAY 0.659574 (-3340 3860);
PAINT MONO (-3340 3860);
DISPLAY INVISIBLE (-3340 3860);
FORCEPROP 1 LASTPIN (-3350 3850) BN 5
J 0
(-3362 3858);
DISPLAY 0.489362 (-3362 3858);
PAINT GREEN (-3362 3858);
FORCEPROP 2 LAST CDS_LIB mstr_standard
J 0
(-3300 3850);
DISPLAY 0.723404 (-3300 3850);
PAINT MONO (-3300 3850);
DISPLAY INVISIBLE (-3300 3850);
FORCEPROP 1 LAST BODY_TYPE PLUMBING
J 0
(-3300 3900);
DISPLAY 0.872340 (-3300 3900);
PAINT GREEN (-3300 3900);
DISPLAY INVISIBLE (-3300 3900);
FORCEPROP 1 LAST HDL_TAP TRUE
J 0
(-2975 3725);
DISPLAY 0.872340 (-2975 3725);
DISPLAY INVISIBLE (-2975 3725);
FORCEPROP 1 LAST PATH I203
J 0
(-3302 3850);
DISPLAY 0.872340 (-3302 3850);
PAINT GREEN (-3302 3850);
DISPLAY INVISIBLE (-3302 3850);
FORCEADD TAP..1
(-3500 3900);
FORCEPROP 3 LASTPIN (-3550 3900) SIG_NAME M_L_CPU0_SA_DQS_DP<5>
J 0
(-3540 3910);
DISPLAY 0.659574 (-3540 3910);
PAINT MONO (-3540 3910);
DISPLAY INVISIBLE (-3540 3910);
FORCEPROP 1 LASTPIN (-3550 3900) BN 5
J 0
(-3562 3908);
DISPLAY 0.489362 (-3562 3908);
PAINT GREEN (-3562 3908);
FORCEPROP 2 LAST CDS_LIB mstr_standard
J 0
(-3500 3900);
DISPLAY 0.723404 (-3500 3900);
PAINT MONO (-3500 3900);
DISPLAY INVISIBLE (-3500 3900);
FORCEPROP 1 LAST BODY_TYPE PLUMBING
J 0
(-3500 3950);
DISPLAY 0.872340 (-3500 3950);
PAINT GREEN (-3500 3950);
DISPLAY INVISIBLE (-3500 3950);
FORCEPROP 1 LAST HDL_TAP TRUE
J 0
(-3175 3775);
DISPLAY 0.872340 (-3175 3775);
DISPLAY INVISIBLE (-3175 3775);
FORCEPROP 1 LAST PATH I204
J 0
(-3502 3900);
DISPLAY 0.872340 (-3502 3900);
PAINT GREEN (-3502 3900);
DISPLAY INVISIBLE (-3502 3900);
FORCEADD TAP..1
(-3500 3700);
FORCEPROP 3 LASTPIN (-3550 3700) SIG_NAME M_L_CPU0_SA_DQS_DP<3>
J 0
(-3540 3710);
DISPLAY 0.659574 (-3540 3710);
PAINT MONO (-3540 3710);
DISPLAY INVISIBLE (-3540 3710);
FORCEPROP 1 LASTPIN (-3550 3700) BN 3
J 0
(-3562 3708);
DISPLAY 0.489362 (-3562 3708);
PAINT GREEN (-3562 3708);
FORCEPROP 2 LAST CDS_LIB mstr_standard
J 0
(-3500 3700);
DISPLAY 0.723404 (-3500 3700);
PAINT MONO (-3500 3700);
DISPLAY INVISIBLE (-3500 3700);
FORCEPROP 1 LAST BODY_TYPE PLUMBING
J 0
(-3500 3750);
DISPLAY 0.872340 (-3500 3750);
PAINT GREEN (-3500 3750);
DISPLAY INVISIBLE (-3500 3750);
FORCEPROP 1 LAST HDL_TAP TRUE
J 0
(-3175 3575);
DISPLAY 0.872340 (-3175 3575);
DISPLAY INVISIBLE (-3175 3575);
FORCEPROP 1 LAST PATH I205
J 0
(-3502 3700);
DISPLAY 0.872340 (-3502 3700);
PAINT GREEN (-3502 3700);
DISPLAY INVISIBLE (-3502 3700);
FORCEADD TAP..1
(-3500 3800);
FORCEPROP 3 LASTPIN (-3550 3800) SIG_NAME M_L_CPU0_SA_DQS_DP<4>
J 0
(-3540 3810);
DISPLAY 0.659574 (-3540 3810);
PAINT MONO (-3540 3810);
DISPLAY INVISIBLE (-3540 3810);
FORCEPROP 1 LASTPIN (-3550 3800) BN 4
J 0
(-3562 3808);
DISPLAY 0.489362 (-3562 3808);
PAINT GREEN (-3562 3808);
FORCEPROP 2 LAST CDS_LIB mstr_standard
J 0
(-3500 3800);
DISPLAY 0.723404 (-3500 3800);
PAINT MONO (-3500 3800);
DISPLAY INVISIBLE (-3500 3800);
FORCEPROP 1 LAST BODY_TYPE PLUMBING
J 0
(-3500 3850);
DISPLAY 0.872340 (-3500 3850);
PAINT GREEN (-3500 3850);
DISPLAY INVISIBLE (-3500 3850);
FORCEPROP 1 LAST HDL_TAP TRUE
J 0
(-3175 3675);
DISPLAY 0.872340 (-3175 3675);
DISPLAY INVISIBLE (-3175 3675);
FORCEPROP 1 LAST PATH I206
J 0
(-3502 3800);
DISPLAY 0.872340 (-3502 3800);
PAINT GREEN (-3502 3800);
DISPLAY INVISIBLE (-3502 3800);
FORCEADD TAP..1
(-3300 3550);
FORCEPROP 3 LASTPIN (-3350 3550) SIG_NAME M_L_CPU0_SA_DQS_DN<2>
J 0
(-3340 3560);
DISPLAY 0.659574 (-3340 3560);
PAINT MONO (-3340 3560);
DISPLAY INVISIBLE (-3340 3560);
FORCEPROP 1 LASTPIN (-3350 3550) BN 2
J 0
(-3362 3558);
DISPLAY 0.489362 (-3362 3558);
PAINT GREEN (-3362 3558);
FORCEPROP 2 LAST CDS_LIB mstr_standard
J 0
(-3300 3550);
DISPLAY 0.723404 (-3300 3550);
PAINT MONO (-3300 3550);
DISPLAY INVISIBLE (-3300 3550);
FORCEPROP 1 LAST BODY_TYPE PLUMBING
J 0
(-3300 3600);
DISPLAY 0.872340 (-3300 3600);
PAINT GREEN (-3300 3600);
DISPLAY INVISIBLE (-3300 3600);
FORCEPROP 1 LAST HDL_TAP TRUE
J 0
(-2975 3425);
DISPLAY 0.872340 (-2975 3425);
DISPLAY INVISIBLE (-2975 3425);
FORCEPROP 1 LAST PATH I207
J 0
(-3302 3550);
DISPLAY 0.872340 (-3302 3550);
PAINT GREEN (-3302 3550);
DISPLAY INVISIBLE (-3302 3550);
FORCEADD TAP..1
(-3300 3650);
FORCEPROP 3 LASTPIN (-3350 3650) SIG_NAME M_L_CPU0_SA_DQS_DN<3>
J 0
(-3340 3660);
DISPLAY 0.659574 (-3340 3660);
PAINT MONO (-3340 3660);
DISPLAY INVISIBLE (-3340 3660);
FORCEPROP 1 LASTPIN (-3350 3650) BN 3
J 0
(-3362 3658);
DISPLAY 0.489362 (-3362 3658);
PAINT GREEN (-3362 3658);
FORCEPROP 2 LAST CDS_LIB mstr_standard
J 0
(-3300 3650);
DISPLAY 0.723404 (-3300 3650);
PAINT MONO (-3300 3650);
DISPLAY INVISIBLE (-3300 3650);
FORCEPROP 1 LAST BODY_TYPE PLUMBING
J 0
(-3300 3700);
DISPLAY 0.872340 (-3300 3700);
PAINT GREEN (-3300 3700);
DISPLAY INVISIBLE (-3300 3700);
FORCEPROP 1 LAST HDL_TAP TRUE
J 0
(-2975 3525);
DISPLAY 0.872340 (-2975 3525);
DISPLAY INVISIBLE (-2975 3525);
FORCEPROP 1 LAST PATH I208
J 0
(-3302 3650);
DISPLAY 0.872340 (-3302 3650);
PAINT GREEN (-3302 3650);
DISPLAY INVISIBLE (-3302 3650);
FORCEADD TAP..1
(-3300 3450);
FORCEPROP 3 LASTPIN (-3350 3450) SIG_NAME M_L_CPU0_SA_DQS_DN<1>
J 0
(-3340 3460);
DISPLAY 0.659574 (-3340 3460);
PAINT MONO (-3340 3460);
DISPLAY INVISIBLE (-3340 3460);
FORCEPROP 1 LASTPIN (-3350 3450) BN 1
J 0
(-3362 3458);
DISPLAY 0.489362 (-3362 3458);
PAINT GREEN (-3362 3458);
FORCEPROP 2 LAST CDS_LIB mstr_standard
J 0
(-3300 3450);
DISPLAY 0.723404 (-3300 3450);
PAINT MONO (-3300 3450);
DISPLAY INVISIBLE (-3300 3450);
FORCEPROP 1 LAST BODY_TYPE PLUMBING
J 0
(-3300 3500);
DISPLAY 0.872340 (-3300 3500);
PAINT GREEN (-3300 3500);
DISPLAY INVISIBLE (-3300 3500);
FORCEPROP 1 LAST HDL_TAP TRUE
J 0
(-2975 3325);
DISPLAY 0.872340 (-2975 3325);
DISPLAY INVISIBLE (-2975 3325);
FORCEPROP 1 LAST PATH I209
J 0
(-3302 3450);
DISPLAY 0.872340 (-3302 3450);
PAINT GREEN (-3302 3450);
DISPLAY INVISIBLE (-3302 3450);
FORCEADD OFFPAGE..1
(-8325 4725);
FORCEPROP 2 LAST $XR0 21 
J 0
(-8546 4725);
DISPLAY 0.638298 (-8546 4725);
PAINT MONO (-8546 4725);
FORCEPROP 2 LAST CDS_LIB mstr_standard
J 0
(-8325 4725);
DISPLAY 0.723404 (-8325 4725);
PAINT MONO (-8325 4725);
DISPLAY INVISIBLE (-8325 4725);
FORCEPROP 1 LAST OFFPAGE TRUE
J 0
(-8000 4600);
DISPLAY 0.872340 (-8000 4600);
PAINT GREEN (-8000 4600);
DISPLAY INVISIBLE (-8000 4600);
FORCEPROP 1 LAST COMMENT_BODY TRUE
J 0
(-8200 4625);
DISPLAY 0.872340 (-8200 4625);
PAINT GREEN (-8200 4625);
DISPLAY INVISIBLE (-8200 4625);
FORCEPROP 2 LAST PATH I21
J 0
(-8275 4800);
DISPLAY 1.021277 (-8275 4800);
DISPLAY INVISIBLE (-8275 4800);
FORCEADD TAP..1
(-3500 3600);
FORCEPROP 3 LASTPIN (-3550 3600) SIG_NAME M_L_CPU0_SA_DQS_DP<2>
J 0
(-3540 3610);
DISPLAY 0.659574 (-3540 3610);
PAINT MONO (-3540 3610);
DISPLAY INVISIBLE (-3540 3610);
FORCEPROP 1 LASTPIN (-3550 3600) BN 2
J 0
(-3562 3608);
DISPLAY 0.489362 (-3562 3608);
PAINT GREEN (-3562 3608);
FORCEPROP 2 LAST CDS_LIB mstr_standard
J 0
(-3500 3600);
DISPLAY 0.723404 (-3500 3600);
PAINT MONO (-3500 3600);
DISPLAY INVISIBLE (-3500 3600);
FORCEPROP 1 LAST BODY_TYPE PLUMBING
J 0
(-3500 3650);
DISPLAY 0.872340 (-3500 3650);
PAINT GREEN (-3500 3650);
DISPLAY INVISIBLE (-3500 3650);
FORCEPROP 1 LAST HDL_TAP TRUE
J 0
(-3175 3475);
DISPLAY 0.872340 (-3175 3475);
DISPLAY INVISIBLE (-3175 3475);
FORCEPROP 1 LAST PATH I210
J 0
(-3502 3600);
DISPLAY 0.872340 (-3502 3600);
PAINT GREEN (-3502 3600);
DISPLAY INVISIBLE (-3502 3600);
FORCEADD TAP..1
(-3500 3500);
FORCEPROP 3 LASTPIN (-3550 3500) SIG_NAME M_L_CPU0_SA_DQS_DP<1>
J 0
(-3540 3510);
DISPLAY 0.659574 (-3540 3510);
PAINT MONO (-3540 3510);
DISPLAY INVISIBLE (-3540 3510);
FORCEPROP 1 LASTPIN (-3550 3500) BN 1
J 0
(-3562 3508);
DISPLAY 0.489362 (-3562 3508);
PAINT GREEN (-3562 3508);
FORCEPROP 2 LAST CDS_LIB mstr_standard
J 0
(-3500 3500);
DISPLAY 0.723404 (-3500 3500);
PAINT MONO (-3500 3500);
DISPLAY INVISIBLE (-3500 3500);
FORCEPROP 1 LAST BODY_TYPE PLUMBING
J 0
(-3500 3550);
DISPLAY 0.872340 (-3500 3550);
PAINT GREEN (-3500 3550);
DISPLAY INVISIBLE (-3500 3550);
FORCEPROP 1 LAST HDL_TAP TRUE
J 0
(-3175 3375);
DISPLAY 0.872340 (-3175 3375);
DISPLAY INVISIBLE (-3175 3375);
FORCEPROP 1 LAST PATH I211
J 0
(-3502 3500);
DISPLAY 0.872340 (-3502 3500);
PAINT GREEN (-3502 3500);
DISPLAY INVISIBLE (-3502 3500);
FORCEADD OFFPAGE..2
(-2500 3250);
FORCEPROP 2 LAST $XR0 21 
J 0
(-2311 3250);
DISPLAY 0.638298 (-2311 3250);
PAINT MONO (-2311 3250);
FORCEPROP 2 LAST CDS_LIB mstr_standard
J 0
(-2500 3250);
DISPLAY 0.723404 (-2500 3250);
PAINT MONO (-2500 3250);
DISPLAY INVISIBLE (-2500 3250);
FORCEPROP 1 LAST OFFPAGE TRUE
J 0
(-2175 3125);
DISPLAY 0.723404 (-2175 3125);
PAINT GREEN (-2175 3125);
DISPLAY INVISIBLE (-2175 3125);
FORCEPROP 1 LAST COMMENT_BODY TRUE
J 0
(-2545 3155);
DISPLAY 0.872340 (-2545 3155);
PAINT GREEN (-2545 3155);
DISPLAY INVISIBLE (-2545 3155);
FORCEPROP 2 LAST PATH I212
J 0
(-2300 3300);
DISPLAY 0.680851 (-2300 3300);
DISPLAY INVISIBLE (-2300 3300);
FORCEADD OFFPAGE..2
(-2500 3300);
FORCEPROP 2 LAST $XR0 21 
J 0
(-2311 3300);
DISPLAY 0.638298 (-2311 3300);
PAINT MONO (-2311 3300);
FORCEPROP 2 LAST CDS_LIB mstr_standard
J 0
(-2500 3300);
DISPLAY 0.723404 (-2500 3300);
PAINT MONO (-2500 3300);
DISPLAY INVISIBLE (-2500 3300);
FORCEPROP 1 LAST OFFPAGE TRUE
J 0
(-2175 3175);
DISPLAY 0.723404 (-2175 3175);
PAINT GREEN (-2175 3175);
DISPLAY INVISIBLE (-2175 3175);
FORCEPROP 1 LAST COMMENT_BODY TRUE
J 0
(-2545 3205);
DISPLAY 0.872340 (-2545 3205);
PAINT GREEN (-2545 3205);
DISPLAY INVISIBLE (-2545 3205);
FORCEPROP 2 LAST PATH I213
J 0
(-2300 3350);
DISPLAY 0.680851 (-2300 3350);
DISPLAY INVISIBLE (-2300 3350);
FORCEADD TAP..1
(-3300 3200);
FORCEPROP 3 LASTPIN (-3350 3200) SIG_NAME M_L_CPU0_SB_DQS_DN<9>
J 0
(-3340 3210);
DISPLAY 0.659574 (-3340 3210);
PAINT MONO (-3340 3210);
DISPLAY INVISIBLE (-3340 3210);
FORCEPROP 1 LASTPIN (-3350 3200) BN 9
J 0
(-3362 3208);
DISPLAY 0.489362 (-3362 3208);
PAINT GREEN (-3362 3208);
FORCEPROP 2 LAST CDS_LIB mstr_standard
J 0
(-3300 3200);
DISPLAY 0.723404 (-3300 3200);
PAINT MONO (-3300 3200);
DISPLAY INVISIBLE (-3300 3200);
FORCEPROP 1 LAST BODY_TYPE PLUMBING
J 0
(-3300 3250);
DISPLAY 0.872340 (-3300 3250);
PAINT GREEN (-3300 3250);
DISPLAY INVISIBLE (-3300 3250);
FORCEPROP 1 LAST HDL_TAP TRUE
J 0
(-2975 3075);
DISPLAY 0.872340 (-2975 3075);
DISPLAY INVISIBLE (-2975 3075);
FORCEPROP 1 LAST PATH I214
J 0
(-3302 3200);
DISPLAY 0.872340 (-3302 3200);
PAINT GREEN (-3302 3200);
DISPLAY INVISIBLE (-3302 3200);
FORCEADD TAP..1
(-3300 3350);
FORCEPROP 3 LASTPIN (-3350 3350) SIG_NAME M_L_CPU0_SA_DQS_DN<0>
J 0
(-3340 3360);
DISPLAY 0.659574 (-3340 3360);
PAINT MONO (-3340 3360);
DISPLAY INVISIBLE (-3340 3360);
FORCEPROP 1 LASTPIN (-3350 3350) BN 0
J 0
(-3362 3358);
DISPLAY 0.489362 (-3362 3358);
PAINT GREEN (-3362 3358);
FORCEPROP 2 LAST CDS_LIB mstr_standard
J 0
(-3300 3350);
DISPLAY 0.723404 (-3300 3350);
PAINT MONO (-3300 3350);
DISPLAY INVISIBLE (-3300 3350);
FORCEPROP 1 LAST BODY_TYPE PLUMBING
J 0
(-3300 3400);
DISPLAY 0.872340 (-3300 3400);
PAINT GREEN (-3300 3400);
DISPLAY INVISIBLE (-3300 3400);
FORCEPROP 1 LAST HDL_TAP TRUE
J 0
(-2975 3225);
DISPLAY 0.872340 (-2975 3225);
DISPLAY INVISIBLE (-2975 3225);
FORCEPROP 1 LAST PATH I215
J 0
(-3302 3350);
DISPLAY 0.872340 (-3302 3350);
PAINT GREEN (-3302 3350);
DISPLAY INVISIBLE (-3302 3350);
FORCEADD TAP..1
(-3500 3400);
FORCEPROP 3 LASTPIN (-3550 3400) SIG_NAME M_L_CPU0_SA_DQS_DP<0>
J 0
(-3540 3410);
DISPLAY 0.659574 (-3540 3410);
PAINT MONO (-3540 3410);
DISPLAY INVISIBLE (-3540 3410);
FORCEPROP 1 LASTPIN (-3550 3400) BN 0
J 0
(-3562 3408);
DISPLAY 0.489362 (-3562 3408);
PAINT GREEN (-3562 3408);
FORCEPROP 2 LAST CDS_LIB mstr_standard
J 0
(-3500 3400);
DISPLAY 0.723404 (-3500 3400);
PAINT MONO (-3500 3400);
DISPLAY INVISIBLE (-3500 3400);
FORCEPROP 1 LAST BODY_TYPE PLUMBING
J 0
(-3500 3450);
DISPLAY 0.872340 (-3500 3450);
PAINT GREEN (-3500 3450);
DISPLAY INVISIBLE (-3500 3450);
FORCEPROP 1 LAST HDL_TAP TRUE
J 0
(-3175 3275);
DISPLAY 0.872340 (-3175 3275);
DISPLAY INVISIBLE (-3175 3275);
FORCEPROP 1 LAST PATH I216
J 0
(-3502 3400);
DISPLAY 0.872340 (-3502 3400);
PAINT GREEN (-3502 3400);
DISPLAY INVISIBLE (-3502 3400);
FORCEADD TAP..1
(-3500 3250);
FORCEPROP 3 LASTPIN (-3550 3250) SIG_NAME M_L_CPU0_SB_DQS_DP<9>
J 0
(-3540 3260);
DISPLAY 0.659574 (-3540 3260);
PAINT MONO (-3540 3260);
DISPLAY INVISIBLE (-3540 3260);
FORCEPROP 1 LASTPIN (-3550 3250) BN 9
J 0
(-3562 3258);
DISPLAY 0.489362 (-3562 3258);
PAINT GREEN (-3562 3258);
FORCEPROP 2 LAST CDS_LIB mstr_standard
J 0
(-3500 3250);
DISPLAY 0.723404 (-3500 3250);
PAINT MONO (-3500 3250);
DISPLAY INVISIBLE (-3500 3250);
FORCEPROP 1 LAST BODY_TYPE PLUMBING
J 0
(-3500 3300);
DISPLAY 0.872340 (-3500 3300);
PAINT GREEN (-3500 3300);
DISPLAY INVISIBLE (-3500 3300);
FORCEPROP 1 LAST HDL_TAP TRUE
J 0
(-3175 3125);
DISPLAY 0.872340 (-3175 3125);
DISPLAY INVISIBLE (-3175 3125);
FORCEPROP 1 LAST PATH I217
J 0
(-3502 3250);
DISPLAY 0.872340 (-3502 3250);
PAINT GREEN (-3502 3250);
DISPLAY INVISIBLE (-3502 3250);
FORCEADD TAP..1
(-3300 3100);
FORCEPROP 3 LASTPIN (-3350 3100) SIG_NAME M_L_CPU0_SB_DQS_DN<8>
J 0
(-3340 3110);
DISPLAY 0.659574 (-3340 3110);
PAINT MONO (-3340 3110);
DISPLAY INVISIBLE (-3340 3110);
FORCEPROP 1 LASTPIN (-3350 3100) BN 8
J 0
(-3362 3108);
DISPLAY 0.489362 (-3362 3108);
PAINT GREEN (-3362 3108);
FORCEPROP 2 LAST CDS_LIB mstr_standard
J 0
(-3300 3100);
DISPLAY 0.723404 (-3300 3100);
PAINT MONO (-3300 3100);
DISPLAY INVISIBLE (-3300 3100);
FORCEPROP 1 LAST BODY_TYPE PLUMBING
J 0
(-3300 3150);
DISPLAY 0.872340 (-3300 3150);
PAINT GREEN (-3300 3150);
DISPLAY INVISIBLE (-3300 3150);
FORCEPROP 1 LAST HDL_TAP TRUE
J 0
(-2975 2975);
DISPLAY 0.872340 (-2975 2975);
DISPLAY INVISIBLE (-2975 2975);
FORCEPROP 1 LAST PATH I218
J 0
(-3302 3100);
DISPLAY 0.872340 (-3302 3100);
PAINT GREEN (-3302 3100);
DISPLAY INVISIBLE (-3302 3100);
FORCEADD TAP..1
(-3300 3000);
FORCEPROP 3 LASTPIN (-3350 3000) SIG_NAME M_L_CPU0_SB_DQS_DN<7>
J 0
(-3340 3010);
DISPLAY 0.659574 (-3340 3010);
PAINT MONO (-3340 3010);
DISPLAY INVISIBLE (-3340 3010);
FORCEPROP 1 LASTPIN (-3350 3000) BN 7
J 0
(-3362 3008);
DISPLAY 0.489362 (-3362 3008);
PAINT GREEN (-3362 3008);
FORCEPROP 2 LAST CDS_LIB mstr_standard
J 0
(-3300 3000);
DISPLAY 0.723404 (-3300 3000);
PAINT MONO (-3300 3000);
DISPLAY INVISIBLE (-3300 3000);
FORCEPROP 1 LAST BODY_TYPE PLUMBING
J 0
(-3300 3050);
DISPLAY 0.872340 (-3300 3050);
PAINT GREEN (-3300 3050);
DISPLAY INVISIBLE (-3300 3050);
FORCEPROP 1 LAST HDL_TAP TRUE
J 0
(-2975 2875);
DISPLAY 0.872340 (-2975 2875);
DISPLAY INVISIBLE (-2975 2875);
FORCEPROP 1 LAST PATH I219
J 0
(-3302 3000);
DISPLAY 0.872340 (-3302 3000);
PAINT GREEN (-3302 3000);
DISPLAY INVISIBLE (-3302 3000);
FORCEADD SCONN288_DDR506112002KQ..1
(-6875 3325);
FORCEPROP 1 LAST LOCATION J67
J 0
(-7325 5400);
DISPLAY 0.468085 (-7325 5400);
PAINT SKYBLUE (-7325 5400);
FORCEPROP 0 LAST $SEC 1
J 0
(-7325 5550);
DISPLAY 0.680851 (-7325 5550);
PAINT MONO (-7325 5550);
DISPLAY INVISIBLE (-7325 5550);
FORCEPROP 2 LAST CDS_SEC 1
J 0
(-7325 5550);
DISPLAY 1.021277 (-7325 5550);
DISPLAY INVISIBLE (-7325 5550);
FORCEPROP 0 LASTPIN (-7475 2725) $PN 62
J 2
(-7485 2735);
DISPLAY 0.680851 (-7485 2735);
PAINT MONO (-7485 2735);
FORCEPROP 0 LASTPIN (-7475 4775) $PN 66
J 2
(-7485 4785);
DISPLAY 0.680851 (-7485 4785);
PAINT MONO (-7485 4785);
FORCEPROP 0 LASTPIN (-7475 4375) $PN 76
J 2
(-7485 4385);
DISPLAY 0.680851 (-7485 4385);
PAINT MONO (-7485 4385);
FORCEPROP 0 LASTPIN (-7475 4825) $PN 211
J 2
(-7485 4835);
DISPLAY 0.680851 (-7485 4835);
PAINT MONO (-7485 4835);
FORCEPROP 0 LASTPIN (-7475 4425) $PN 221
J 2
(-7485 4435);
DISPLAY 0.680851 (-7485 4435);
PAINT MONO (-7485 4435);
FORCEPROP 0 LASTPIN (-7475 4875) $PN 68
J 2
(-7485 4885);
DISPLAY 0.680851 (-7485 4885);
PAINT MONO (-7485 4885);
FORCEPROP 0 LASTPIN (-7475 4475) $PN 78
J 2
(-7485 4485);
DISPLAY 0.680851 (-7485 4485);
PAINT MONO (-7485 4485);
FORCEPROP 0 LASTPIN (-7475 4925) $PN 213
J 2
(-7485 4935);
DISPLAY 0.680851 (-7485 4935);
PAINT MONO (-7485 4935);
FORCEPROP 0 LASTPIN (-7475 4525) $PN 223
J 2
(-7485 4535);
DISPLAY 0.680851 (-7485 4535);
PAINT MONO (-7485 4535);
FORCEPROP 0 LASTPIN (-7475 4975) $PN 70
J 2
(-7485 4985);
DISPLAY 0.680851 (-7485 4985);
PAINT MONO (-7485 4985);
FORCEPROP 0 LASTPIN (-7475 4575) $PN 80
J 2
(-7485 4585);
DISPLAY 0.680851 (-7485 4585);
PAINT MONO (-7485 4585);
FORCEPROP 0 LASTPIN (-7475 5025) $PN 215
J 2
(-7485 5035);
DISPLAY 0.680851 (-7485 5035);
PAINT MONO (-7485 5035);
FORCEPROP 0 LASTPIN (-7475 4625) $PN 225
J 2
(-7485 4635);
DISPLAY 0.680851 (-7485 4635);
PAINT MONO (-7485 4635);
FORCEPROP 0 LASTPIN (-7475 5075) $PN 72
J 2
(-7485 5085);
DISPLAY 0.680851 (-7485 5085);
PAINT MONO (-7485 5085);
FORCEPROP 0 LASTPIN (-7475 4675) $PN 82
J 2
(-7485 4685);
DISPLAY 0.680851 (-7485 4685);
PAINT MONO (-7485 4685);
FORCEPROP 0 LASTPIN (-7475 3325) $PN 51
J 2
(-7485 3335);
DISPLAY 0.680851 (-7485 3335);
PAINT MONO (-7485 3335);
FORCEPROP 0 LASTPIN (-7475 2875) $PN 96
J 2
(-7485 2885);
DISPLAY 0.680851 (-7485 2885);
PAINT MONO (-7485 2885);
FORCEPROP 0 LASTPIN (-7475 3375) $PN 53
J 2
(-7485 3385);
DISPLAY 0.680851 (-7485 3385);
PAINT MONO (-7485 3385);
FORCEPROP 0 LASTPIN (-7475 2925) $PN 98
J 2
(-7485 2935);
DISPLAY 0.680851 (-7485 2935);
PAINT MONO (-7485 2935);
FORCEPROP 0 LASTPIN (-7475 3425) $PN 196
J 2
(-7485 3435);
DISPLAY 0.680851 (-7485 3435);
PAINT MONO (-7485 3435);
FORCEPROP 0 LASTPIN (-7475 2975) $PN 241
J 2
(-7485 2985);
DISPLAY 0.680851 (-7485 2985);
PAINT MONO (-7485 2985);
FORCEPROP 0 LASTPIN (-7475 3475) $PN 198
J 2
(-7485 3485);
DISPLAY 0.680851 (-7485 3485);
PAINT MONO (-7485 3485);
FORCEPROP 0 LASTPIN (-7475 3025) $PN 243
J 2
(-7485 3035);
DISPLAY 0.680851 (-7485 3035);
PAINT MONO (-7485 3035);
FORCEPROP 0 LASTPIN (-7475 3525) $PN 58
J 2
(-7485 3535);
DISPLAY 0.680851 (-7485 3535);
PAINT MONO (-7485 3535);
FORCEPROP 0 LASTPIN (-7475 3075) $PN 89
J 2
(-7485 3085);
DISPLAY 0.680851 (-7485 3085);
PAINT MONO (-7485 3085);
FORCEPROP 0 LASTPIN (-7475 3575) $PN 60
J 2
(-7485 3585);
DISPLAY 0.680851 (-7485 3585);
PAINT MONO (-7485 3585);
FORCEPROP 0 LASTPIN (-7475 3125) $PN 91
J 2
(-7485 3135);
DISPLAY 0.680851 (-7485 3135);
PAINT MONO (-7485 3135);
FORCEPROP 0 LASTPIN (-7475 3625) $PN 203
J 2
(-7485 3635);
DISPLAY 0.680851 (-7485 3635);
PAINT MONO (-7485 3635);
FORCEPROP 0 LASTPIN (-7475 3175) $PN 234
J 2
(-7485 3185);
DISPLAY 0.680851 (-7485 3185);
PAINT MONO (-7485 3185);
FORCEPROP 0 LASTPIN (-7475 3675) $PN 205
J 2
(-7485 3685);
DISPLAY 0.680851 (-7485 3685);
PAINT MONO (-7485 3685);
FORCEPROP 0 LASTPIN (-7475 3225) $PN 236
J 2
(-7485 3235);
DISPLAY 0.680851 (-7485 3235);
PAINT MONO (-7485 3235);
FORCEPROP 0 LASTPIN (-7475 3775) $PN 218
J 2
(-7485 3785);
DISPLAY 0.680851 (-7485 3785);
PAINT MONO (-7485 3785);
FORCEPROP 0 LASTPIN (-7475 3825) $PN 217
J 2
(-7485 3835);
DISPLAY 0.680851 (-7485 3835);
PAINT MONO (-7485 3835);
FORCEPROP 0 LASTPIN (-7475 4075) $PN 64
J 2
(-7485 4085);
DISPLAY 0.680851 (-7485 4085);
PAINT MONO (-7485 4085);
FORCEPROP 0 LASTPIN (-7475 3925) $PN 84
J 2
(-7485 3935);
DISPLAY 0.680851 (-7485 3935);
PAINT MONO (-7485 3935);
FORCEPROP 0 LASTPIN (-7475 4125) $PN 209
J 2
(-7485 4135);
DISPLAY 0.680851 (-7485 4135);
PAINT MONO (-7485 4135);
FORCEPROP 0 LASTPIN (-7475 3975) $PN 229
J 2
(-7485 3985);
DISPLAY 0.680851 (-7485 3985);
PAINT MONO (-7485 3985);
FORCEPROP 0 LASTPIN (-6275 3525) $PN 7
J 0
(-6265 3535);
DISPLAY 0.680851 (-6265 3535);
PAINT MONO (-6265 3535);
FORCEPROP 0 LASTPIN (-6275 1875) $PN 100
J 0
(-6265 1885);
DISPLAY 0.680851 (-6265 1885);
PAINT MONO (-6265 1885);
FORCEPROP 0 LASTPIN (-6275 3575) $PN 9
J 0
(-6265 3585);
DISPLAY 0.680851 (-6265 3585);
PAINT MONO (-6265 3585);
FORCEPROP 0 LASTPIN (-6275 1925) $PN 102
J 0
(-6265 1935);
DISPLAY 0.680851 (-6265 1935);
PAINT MONO (-6265 1935);
FORCEPROP 0 LASTPIN (-6275 3625) $PN 152
J 0
(-6265 3635);
DISPLAY 0.680851 (-6265 3635);
PAINT MONO (-6265 3635);
FORCEPROP 0 LASTPIN (-6275 1975) $PN 245
J 0
(-6265 1985);
DISPLAY 0.680851 (-6265 1985);
PAINT MONO (-6265 1985);
FORCEPROP 0 LASTPIN (-6275 3675) $PN 154
J 0
(-6265 3685);
DISPLAY 0.680851 (-6265 3685);
PAINT MONO (-6265 3685);
FORCEPROP 0 LASTPIN (-6275 2025) $PN 247
J 0
(-6265 2035);
DISPLAY 0.680851 (-6265 2035);
PAINT MONO (-6265 2035);
FORCEPROP 0 LASTPIN (-6275 3725) $PN 14
J 0
(-6265 3735);
DISPLAY 0.680851 (-6265 3735);
PAINT MONO (-6265 3735);
FORCEPROP 0 LASTPIN (-6275 2075) $PN 107
J 0
(-6265 2085);
DISPLAY 0.680851 (-6265 2085);
PAINT MONO (-6265 2085);
FORCEPROP 0 LASTPIN (-6275 3775) $PN 16
J 0
(-6265 3785);
DISPLAY 0.680851 (-6265 3785);
PAINT MONO (-6265 3785);
FORCEPROP 0 LASTPIN (-6275 2125) $PN 109
J 0
(-6265 2135);
DISPLAY 0.680851 (-6265 2135);
PAINT MONO (-6265 2135);
FORCEPROP 0 LASTPIN (-6275 3825) $PN 159
J 0
(-6265 3835);
DISPLAY 0.680851 (-6265 3835);
PAINT MONO (-6265 3835);
FORCEPROP 0 LASTPIN (-6275 2175) $PN 252
J 0
(-6265 2185);
DISPLAY 0.680851 (-6265 2185);
PAINT MONO (-6265 2185);
FORCEPROP 0 LASTPIN (-6275 3875) $PN 161
J 0
(-6265 3885);
DISPLAY 0.680851 (-6265 3885);
PAINT MONO (-6265 3885);
FORCEPROP 0 LASTPIN (-6275 2225) $PN 254
J 0
(-6265 2235);
DISPLAY 0.680851 (-6265 2235);
PAINT MONO (-6265 2235);
FORCEPROP 0 LASTPIN (-6275 3925) $PN 18
J 0
(-6265 3935);
DISPLAY 0.680851 (-6265 3935);
PAINT MONO (-6265 3935);
FORCEPROP 0 LASTPIN (-6275 2275) $PN 111
J 0
(-6265 2285);
DISPLAY 0.680851 (-6265 2285);
PAINT MONO (-6265 2285);
FORCEPROP 0 LASTPIN (-6275 3975) $PN 20
J 0
(-6265 3985);
DISPLAY 0.680851 (-6265 3985);
PAINT MONO (-6265 3985);
FORCEPROP 0 LASTPIN (-6275 2325) $PN 113
J 0
(-6265 2335);
DISPLAY 0.680851 (-6265 2335);
PAINT MONO (-6265 2335);
FORCEPROP 0 LASTPIN (-6275 4025) $PN 163
J 0
(-6265 4035);
DISPLAY 0.680851 (-6265 4035);
PAINT MONO (-6265 4035);
FORCEPROP 0 LASTPIN (-6275 2375) $PN 256
J 0
(-6265 2385);
DISPLAY 0.680851 (-6265 2385);
PAINT MONO (-6265 2385);
FORCEPROP 0 LASTPIN (-6275 4075) $PN 165
J 0
(-6265 4085);
DISPLAY 0.680851 (-6265 4085);
PAINT MONO (-6265 4085);
FORCEPROP 0 LASTPIN (-6275 2425) $PN 258
J 0
(-6265 2435);
DISPLAY 0.680851 (-6265 2435);
PAINT MONO (-6265 2435);
FORCEPROP 0 LASTPIN (-6275 4125) $PN 25
J 0
(-6265 4135);
DISPLAY 0.680851 (-6265 4135);
PAINT MONO (-6265 4135);
FORCEPROP 0 LASTPIN (-6275 2475) $PN 118
J 0
(-6265 2485);
DISPLAY 0.680851 (-6265 2485);
PAINT MONO (-6265 2485);
FORCEPROP 0 LASTPIN (-6275 4175) $PN 27
J 0
(-6265 4185);
DISPLAY 0.680851 (-6265 4185);
PAINT MONO (-6265 4185);
FORCEPROP 0 LASTPIN (-6275 2525) $PN 120
J 0
(-6265 2535);
DISPLAY 0.680851 (-6265 2535);
PAINT MONO (-6265 2535);
FORCEPROP 0 LASTPIN (-6275 4225) $PN 170
J 0
(-6265 4235);
DISPLAY 0.680851 (-6265 4235);
PAINT MONO (-6265 4235);
FORCEPROP 0 LASTPIN (-6275 2575) $PN 263
J 0
(-6265 2585);
DISPLAY 0.680851 (-6265 2585);
PAINT MONO (-6265 2585);
FORCEPROP 0 LASTPIN (-6275 4275) $PN 172
J 0
(-6265 4285);
DISPLAY 0.680851 (-6265 4285);
PAINT MONO (-6265 4285);
FORCEPROP 0 LASTPIN (-6275 2625) $PN 265
J 0
(-6265 2635);
DISPLAY 0.680851 (-6265 2635);
PAINT MONO (-6265 2635);
FORCEPROP 0 LASTPIN (-6275 4325) $PN 29
J 0
(-6265 4335);
DISPLAY 0.680851 (-6265 4335);
PAINT MONO (-6265 4335);
FORCEPROP 0 LASTPIN (-6275 2675) $PN 122
J 0
(-6265 2685);
DISPLAY 0.680851 (-6265 2685);
PAINT MONO (-6265 2685);
FORCEPROP 0 LASTPIN (-6275 4375) $PN 31
J 0
(-6265 4385);
DISPLAY 0.680851 (-6265 4385);
PAINT MONO (-6265 4385);
FORCEPROP 0 LASTPIN (-6275 2725) $PN 124
J 0
(-6265 2735);
DISPLAY 0.680851 (-6265 2735);
PAINT MONO (-6265 2735);
FORCEPROP 0 LASTPIN (-6275 4425) $PN 174
J 0
(-6265 4435);
DISPLAY 0.680851 (-6265 4435);
PAINT MONO (-6265 4435);
FORCEPROP 0 LASTPIN (-6275 2775) $PN 267
J 0
(-6265 2785);
DISPLAY 0.680851 (-6265 2785);
PAINT MONO (-6265 2785);
FORCEPROP 0 LASTPIN (-6275 4475) $PN 176
J 0
(-6265 4485);
DISPLAY 0.680851 (-6265 4485);
PAINT MONO (-6265 4485);
FORCEPROP 0 LASTPIN (-6275 2825) $PN 269
J 0
(-6265 2835);
DISPLAY 0.680851 (-6265 2835);
PAINT MONO (-6265 2835);
FORCEPROP 0 LASTPIN (-6275 4525) $PN 36
J 0
(-6265 4535);
DISPLAY 0.680851 (-6265 4535);
PAINT MONO (-6265 4535);
FORCEPROP 0 LASTPIN (-6275 2875) $PN 129
J 0
(-6265 2885);
DISPLAY 0.680851 (-6265 2885);
PAINT MONO (-6265 2885);
FORCEPROP 0 LASTPIN (-6275 4575) $PN 38
J 0
(-6265 4585);
DISPLAY 0.680851 (-6265 4585);
PAINT MONO (-6265 4585);
FORCEPROP 0 LASTPIN (-6275 2925) $PN 131
J 0
(-6265 2935);
DISPLAY 0.680851 (-6265 2935);
PAINT MONO (-6265 2935);
FORCEPROP 0 LASTPIN (-6275 4625) $PN 181
J 0
(-6265 4635);
DISPLAY 0.680851 (-6265 4635);
PAINT MONO (-6265 4635);
FORCEPROP 0 LASTPIN (-6275 2975) $PN 274
J 0
(-6265 2985);
DISPLAY 0.680851 (-6265 2985);
PAINT MONO (-6265 2985);
FORCEPROP 0 LASTPIN (-6275 4675) $PN 183
J 0
(-6265 4685);
DISPLAY 0.680851 (-6265 4685);
PAINT MONO (-6265 4685);
FORCEPROP 0 LASTPIN (-6275 3025) $PN 276
J 0
(-6265 3035);
DISPLAY 0.680851 (-6265 3035);
PAINT MONO (-6265 3035);
FORCEPROP 0 LASTPIN (-6275 4725) $PN 40
J 0
(-6265 4735);
DISPLAY 0.680851 (-6265 4735);
PAINT MONO (-6265 4735);
FORCEPROP 0 LASTPIN (-6275 3075) $PN 133
J 0
(-6265 3085);
DISPLAY 0.680851 (-6265 3085);
PAINT MONO (-6265 3085);
FORCEPROP 0 LASTPIN (-6275 4775) $PN 42
J 0
(-6265 4785);
DISPLAY 0.680851 (-6265 4785);
PAINT MONO (-6265 4785);
FORCEPROP 0 LASTPIN (-6275 3125) $PN 135
J 0
(-6265 3135);
DISPLAY 0.680851 (-6265 3135);
PAINT MONO (-6265 3135);
FORCEPROP 0 LASTPIN (-6275 4825) $PN 185
J 0
(-6265 4835);
DISPLAY 0.680851 (-6265 4835);
PAINT MONO (-6265 4835);
FORCEPROP 0 LASTPIN (-6275 3175) $PN 278
J 0
(-6265 3185);
DISPLAY 0.680851 (-6265 3185);
PAINT MONO (-6265 3185);
FORCEPROP 0 LASTPIN (-6275 4875) $PN 187
J 0
(-6265 4885);
DISPLAY 0.680851 (-6265 4885);
PAINT MONO (-6265 4885);
FORCEPROP 0 LASTPIN (-6275 3225) $PN 280
J 0
(-6265 3235);
DISPLAY 0.680851 (-6265 3235);
PAINT MONO (-6265 3235);
FORCEPROP 0 LASTPIN (-6275 4925) $PN 47
J 0
(-6265 4935);
DISPLAY 0.680851 (-6265 4935);
PAINT MONO (-6265 4935);
FORCEPROP 0 LASTPIN (-6275 3275) $PN 140
J 0
(-6265 3285);
DISPLAY 0.680851 (-6265 3285);
PAINT MONO (-6265 3285);
FORCEPROP 0 LASTPIN (-6275 4975) $PN 49
J 0
(-6265 4985);
DISPLAY 0.680851 (-6265 4985);
PAINT MONO (-6265 4985);
FORCEPROP 0 LASTPIN (-6275 3325) $PN 142
J 0
(-6265 3335);
DISPLAY 0.680851 (-6265 3335);
PAINT MONO (-6265 3335);
FORCEPROP 0 LASTPIN (-6275 5025) $PN 192
J 0
(-6265 5035);
DISPLAY 0.680851 (-6265 5035);
PAINT MONO (-6265 5035);
FORCEPROP 0 LASTPIN (-6275 3375) $PN 285
J 0
(-6265 3385);
DISPLAY 0.680851 (-6265 3385);
PAINT MONO (-6265 3385);
FORCEPROP 0 LASTPIN (-6275 5075) $PN 194
J 0
(-6265 5085);
DISPLAY 0.680851 (-6265 5085);
PAINT MONO (-6265 5085);
FORCEPROP 0 LASTPIN (-6275 3425) $PN 287
J 0
(-6265 3435);
DISPLAY 0.680851 (-6265 3435);
PAINT MONO (-6265 3435);
FORCEPROP 0 LASTPIN (-7475 2575) $PN 148
J 2
(-7485 2585);
DISPLAY 0.680851 (-7485 2585);
PAINT MONO (-7485 2585);
FORCEPROP 0 LASTPIN (-7475 2475) $PN 4
J 2
(-7485 2485);
DISPLAY 0.680851 (-7485 2485);
PAINT MONO (-7485 2485);
FORCEPROP 0 LASTPIN (-7475 2525) $PN 5
J 2
(-7485 2535);
DISPLAY 0.680851 (-7485 2535);
PAINT MONO (-7485 2535);
FORCEPROP 0 LASTPIN (-7475 1675) $PN 86
J 2
(-7485 1685);
DISPLAY 0.680851 (-7485 1685);
PAINT MONO (-7485 1685);
FORCEPROP 0 LASTPIN (-7475 1625) $PN 87
J 2
(-7485 1635);
DISPLAY 0.680851 (-7485 1635);
PAINT MONO (-7485 1635);
FORCEPROP 0 LASTPIN (-7475 4275) $PN 74
J 2
(-7485 4285);
DISPLAY 0.680851 (-7485 4285);
PAINT MONO (-7485 4285);
FORCEPROP 0 LASTPIN (-7475 4225) $PN 227
J 2
(-7485 4235);
DISPLAY 0.680851 (-7485 4235);
PAINT MONO (-7485 4235);
FORCEPROP 0 LASTPIN (-7475 2225) $PN 147
J 2
(-7485 2235);
DISPLAY 0.680851 (-7485 2235);
PAINT MONO (-7485 2235);
FORCEPROP 0 LASTPIN (-7475 2775) $PN 207
J 2
(-7485 2785);
DISPLAY 0.680851 (-7485 2785);
PAINT MONO (-7485 2785);
FORCEPROP 0 LASTPIN (-7475 1825) $PN 2
J 2
(-7485 1835);
DISPLAY 0.680851 (-7485 1835);
PAINT MONO (-7485 1835);
FORCEPROP 0 LASTPIN (-7475 1875) $PN 144
J 2
(-7485 1885);
DISPLAY 0.680851 (-7485 1885);
PAINT MONO (-7485 1885);
FORCEPROP 0 LASTPIN (-7475 1925) $PN 149
J 2
(-7485 1935);
DISPLAY 0.680851 (-7485 1935);
PAINT MONO (-7485 1935);
FORCEPROP 0 LASTPIN (-7475 1975) $PN 150
J 2
(-7485 1985);
DISPLAY 0.680851 (-7485 1985);
PAINT MONO (-7485 1985);
FORCEPROP 0 LASTPIN (-7475 2025) $PN 220
J 2
(-7485 2035);
DISPLAY 0.680851 (-7485 2035);
PAINT MONO (-7485 2035);
FORCEPROP 0 LASTPIN (-7475 2075) $PN 231
J 2
(-7485 2085);
DISPLAY 0.680851 (-7485 2085);
PAINT MONO (-7485 2085);
FORCEPROP 0 LASTPIN (-7475 2125) $PN 232
J 2
(-7485 2135);
DISPLAY 0.680851 (-7485 2135);
PAINT MONO (-7485 2135);
FORCEPROP 0 LASTPIN (-7475 2625) $PN 3
J 2
(-7485 2635);
DISPLAY 0.680851 (-7485 2635);
PAINT MONO (-7485 2635);
FORCEPROP 2 LAST PART_TYPE SMLF
J 0
(-7325 5500);
DISPLAY 1.021277 (-7325 5500);
FORCEPROP 2 LAST VALUE SCONN288_DDR506112002KQ
J 0
(-7325 5450);
DISPLAY 0.489362 (-7325 5450);
PAINT SKYBLUE (-7325 5450);
FORCEPROP 1 LAST MATERIAL IO
J 0
(-7325 5250);
DISPLAY 0.468085 (-7325 5250);
PAINT SKYBLUE (-7325 5250);
FORCEPROP 1 LAST CDS_LMAN_SYM_OUTLINE -450,1900,450,-1850
J 0
(-6875 3325);
DISPLAY 0.468085 (-6875 3325);
PAINT GREEN (-6875 3325);
DISPLAY INVISIBLE (-6875 3325);
FORCEPROP 1 LAST NEEDS_NO_SIZE TRUE
J 0
(-6875 3325);
DISPLAY 0.723404 (-6875 3325);
PAINT GREEN (-6875 3325);
DISPLAY INVISIBLE (-6875 3325);
FORCEPROP 2 LAST CDS_LIB pure_quanta
J 0
(-6875 3325);
DISPLAY INVISIBLE (-6875 3325);
FORCEPROP 1 LAST PATH I22
J 0
(-6875 3325);
DISPLAY 0.723404 (-6875 3325);
PAINT GREEN (-6875 3325);
DISPLAY INVISIBLE (-6875 3325);
FORCEPROP 1 LAST PART_NUMBER DFHST8FS479
J 0
(-7325 5325);
DISPLAY 0.468085 (-7325 5325);
PAINT SKYBLUE (-7325 5325);
DISPLAY INVISIBLE (-7325 5325);
FORCEADD TAP..1
(-3500 3150);
FORCEPROP 3 LASTPIN (-3550 3150) SIG_NAME M_L_CPU0_SB_DQS_DP<8>
J 0
(-3540 3160);
DISPLAY 0.659574 (-3540 3160);
PAINT MONO (-3540 3160);
DISPLAY INVISIBLE (-3540 3160);
FORCEPROP 1 LASTPIN (-3550 3150) BN 8
J 0
(-3562 3158);
DISPLAY 0.489362 (-3562 3158);
PAINT GREEN (-3562 3158);
FORCEPROP 2 LAST CDS_LIB mstr_standard
J 0
(-3500 3150);
DISPLAY 0.723404 (-3500 3150);
PAINT MONO (-3500 3150);
DISPLAY INVISIBLE (-3500 3150);
FORCEPROP 1 LAST BODY_TYPE PLUMBING
J 0
(-3500 3200);
DISPLAY 0.872340 (-3500 3200);
PAINT GREEN (-3500 3200);
DISPLAY INVISIBLE (-3500 3200);
FORCEPROP 1 LAST HDL_TAP TRUE
J 0
(-3175 3025);
DISPLAY 0.872340 (-3175 3025);
DISPLAY INVISIBLE (-3175 3025);
FORCEPROP 1 LAST PATH I220
J 0
(-3502 3150);
DISPLAY 0.872340 (-3502 3150);
PAINT GREEN (-3502 3150);
DISPLAY INVISIBLE (-3502 3150);
FORCEADD TAP..1
(-3500 3050);
FORCEPROP 3 LASTPIN (-3550 3050) SIG_NAME M_L_CPU0_SB_DQS_DP<7>
J 0
(-3540 3060);
DISPLAY 0.659574 (-3540 3060);
PAINT MONO (-3540 3060);
DISPLAY INVISIBLE (-3540 3060);
FORCEPROP 1 LASTPIN (-3550 3050) BN 7
J 0
(-3562 3058);
DISPLAY 0.489362 (-3562 3058);
PAINT GREEN (-3562 3058);
FORCEPROP 2 LAST CDS_LIB mstr_standard
J 0
(-3500 3050);
DISPLAY 0.723404 (-3500 3050);
PAINT MONO (-3500 3050);
DISPLAY INVISIBLE (-3500 3050);
FORCEPROP 1 LAST BODY_TYPE PLUMBING
J 0
(-3500 3100);
DISPLAY 0.872340 (-3500 3100);
PAINT GREEN (-3500 3100);
DISPLAY INVISIBLE (-3500 3100);
FORCEPROP 1 LAST HDL_TAP TRUE
J 0
(-3175 2925);
DISPLAY 0.872340 (-3175 2925);
DISPLAY INVISIBLE (-3175 2925);
FORCEPROP 1 LAST PATH I221
J 0
(-3502 3050);
DISPLAY 0.872340 (-3502 3050);
PAINT GREEN (-3502 3050);
DISPLAY INVISIBLE (-3502 3050);
FORCEADD TAP..1
(-3500 2950);
FORCEPROP 3 LASTPIN (-3550 2950) SIG_NAME M_L_CPU0_SB_DQS_DP<6>
J 0
(-3540 2960);
DISPLAY 0.659574 (-3540 2960);
PAINT MONO (-3540 2960);
DISPLAY INVISIBLE (-3540 2960);
FORCEPROP 1 LASTPIN (-3550 2950) BN 6
J 0
(-3562 2958);
DISPLAY 0.489362 (-3562 2958);
PAINT GREEN (-3562 2958);
FORCEPROP 2 LAST CDS_LIB mstr_standard
J 0
(-3500 2950);
DISPLAY 0.723404 (-3500 2950);
PAINT MONO (-3500 2950);
DISPLAY INVISIBLE (-3500 2950);
FORCEPROP 1 LAST BODY_TYPE PLUMBING
J 0
(-3500 3000);
DISPLAY 0.872340 (-3500 3000);
PAINT GREEN (-3500 3000);
DISPLAY INVISIBLE (-3500 3000);
FORCEPROP 1 LAST HDL_TAP TRUE
J 0
(-3175 2825);
DISPLAY 0.872340 (-3175 2825);
DISPLAY INVISIBLE (-3175 2825);
FORCEPROP 1 LAST PATH I222
J 0
(-3502 2950);
DISPLAY 0.872340 (-3502 2950);
PAINT GREEN (-3502 2950);
DISPLAY INVISIBLE (-3502 2950);
FORCEADD TAP..1
(-3300 2800);
FORCEPROP 3 LASTPIN (-3350 2800) SIG_NAME M_L_CPU0_SB_DQS_DN<5>
J 0
(-3340 2810);
DISPLAY 0.659574 (-3340 2810);
PAINT MONO (-3340 2810);
DISPLAY INVISIBLE (-3340 2810);
FORCEPROP 1 LASTPIN (-3350 2800) BN 5
J 0
(-3362 2808);
DISPLAY 0.489362 (-3362 2808);
PAINT GREEN (-3362 2808);
FORCEPROP 2 LAST CDS_LIB mstr_standard
J 0
(-3300 2800);
DISPLAY 0.723404 (-3300 2800);
PAINT MONO (-3300 2800);
DISPLAY INVISIBLE (-3300 2800);
FORCEPROP 1 LAST BODY_TYPE PLUMBING
J 0
(-3300 2850);
DISPLAY 0.872340 (-3300 2850);
PAINT GREEN (-3300 2850);
DISPLAY INVISIBLE (-3300 2850);
FORCEPROP 1 LAST HDL_TAP TRUE
J 0
(-2975 2675);
DISPLAY 0.872340 (-2975 2675);
DISPLAY INVISIBLE (-2975 2675);
FORCEPROP 1 LAST PATH I223
J 0
(-3302 2800);
DISPLAY 0.872340 (-3302 2800);
PAINT GREEN (-3302 2800);
DISPLAY INVISIBLE (-3302 2800);
FORCEADD TAP..1
(-3300 2900);
FORCEPROP 3 LASTPIN (-3350 2900) SIG_NAME M_L_CPU0_SB_DQS_DN<6>
J 0
(-3340 2910);
DISPLAY 0.659574 (-3340 2910);
PAINT MONO (-3340 2910);
DISPLAY INVISIBLE (-3340 2910);
FORCEPROP 1 LASTPIN (-3350 2900) BN 6
J 0
(-3362 2908);
DISPLAY 0.489362 (-3362 2908);
PAINT GREEN (-3362 2908);
FORCEPROP 2 LAST CDS_LIB mstr_standard
J 0
(-3300 2900);
DISPLAY 0.723404 (-3300 2900);
PAINT MONO (-3300 2900);
DISPLAY INVISIBLE (-3300 2900);
FORCEPROP 1 LAST BODY_TYPE PLUMBING
J 0
(-3300 2950);
DISPLAY 0.872340 (-3300 2950);
PAINT GREEN (-3300 2950);
DISPLAY INVISIBLE (-3300 2950);
FORCEPROP 1 LAST HDL_TAP TRUE
J 0
(-2975 2775);
DISPLAY 0.872340 (-2975 2775);
DISPLAY INVISIBLE (-2975 2775);
FORCEPROP 1 LAST PATH I224
J 0
(-3302 2900);
DISPLAY 0.872340 (-3302 2900);
PAINT GREEN (-3302 2900);
DISPLAY INVISIBLE (-3302 2900);
FORCEADD TAP..1
(-3300 2700);
FORCEPROP 3 LASTPIN (-3350 2700) SIG_NAME M_L_CPU0_SB_DQS_DN<4>
J 0
(-3340 2710);
DISPLAY 0.659574 (-3340 2710);
PAINT MONO (-3340 2710);
DISPLAY INVISIBLE (-3340 2710);
FORCEPROP 1 LASTPIN (-3350 2700) BN 4
J 0
(-3362 2708);
DISPLAY 0.489362 (-3362 2708);
PAINT GREEN (-3362 2708);
FORCEPROP 2 LAST CDS_LIB mstr_standard
J 0
(-3300 2700);
DISPLAY 0.723404 (-3300 2700);
PAINT MONO (-3300 2700);
DISPLAY INVISIBLE (-3300 2700);
FORCEPROP 1 LAST BODY_TYPE PLUMBING
J 0
(-3300 2750);
DISPLAY 0.872340 (-3300 2750);
PAINT GREEN (-3300 2750);
DISPLAY INVISIBLE (-3300 2750);
FORCEPROP 1 LAST HDL_TAP TRUE
J 0
(-2975 2575);
DISPLAY 0.872340 (-2975 2575);
DISPLAY INVISIBLE (-2975 2575);
FORCEPROP 1 LAST PATH I225
J 0
(-3302 2700);
DISPLAY 0.872340 (-3302 2700);
PAINT GREEN (-3302 2700);
DISPLAY INVISIBLE (-3302 2700);
FORCEADD TAP..1
(-3500 2850);
FORCEPROP 3 LASTPIN (-3550 2850) SIG_NAME M_L_CPU0_SB_DQS_DP<5>
J 0
(-3540 2860);
DISPLAY 0.659574 (-3540 2860);
PAINT MONO (-3540 2860);
DISPLAY INVISIBLE (-3540 2860);
FORCEPROP 1 LASTPIN (-3550 2850) BN 5
J 0
(-3562 2858);
DISPLAY 0.489362 (-3562 2858);
PAINT GREEN (-3562 2858);
FORCEPROP 2 LAST CDS_LIB mstr_standard
J 0
(-3500 2850);
DISPLAY 0.723404 (-3500 2850);
PAINT MONO (-3500 2850);
DISPLAY INVISIBLE (-3500 2850);
FORCEPROP 1 LAST BODY_TYPE PLUMBING
J 0
(-3500 2900);
DISPLAY 0.872340 (-3500 2900);
PAINT GREEN (-3500 2900);
DISPLAY INVISIBLE (-3500 2900);
FORCEPROP 1 LAST HDL_TAP TRUE
J 0
(-3175 2725);
DISPLAY 0.872340 (-3175 2725);
DISPLAY INVISIBLE (-3175 2725);
FORCEPROP 1 LAST PATH I226
J 0
(-3502 2850);
DISPLAY 0.872340 (-3502 2850);
PAINT GREEN (-3502 2850);
DISPLAY INVISIBLE (-3502 2850);
FORCEADD TAP..1
(-3500 2750);
FORCEPROP 3 LASTPIN (-3550 2750) SIG_NAME M_L_CPU0_SB_DQS_DP<4>
J 0
(-3540 2760);
DISPLAY 0.659574 (-3540 2760);
PAINT MONO (-3540 2760);
DISPLAY INVISIBLE (-3540 2760);
FORCEPROP 1 LASTPIN (-3550 2750) BN 4
J 0
(-3562 2758);
DISPLAY 0.489362 (-3562 2758);
PAINT GREEN (-3562 2758);
FORCEPROP 2 LAST CDS_LIB mstr_standard
J 0
(-3500 2750);
DISPLAY 0.723404 (-3500 2750);
PAINT MONO (-3500 2750);
DISPLAY INVISIBLE (-3500 2750);
FORCEPROP 1 LAST BODY_TYPE PLUMBING
J 0
(-3500 2800);
DISPLAY 0.872340 (-3500 2800);
PAINT GREEN (-3500 2800);
DISPLAY INVISIBLE (-3500 2800);
FORCEPROP 1 LAST HDL_TAP TRUE
J 0
(-3175 2625);
DISPLAY 0.872340 (-3175 2625);
DISPLAY INVISIBLE (-3175 2625);
FORCEPROP 1 LAST PATH I227
J 0
(-3502 2750);
DISPLAY 0.872340 (-3502 2750);
PAINT GREEN (-3502 2750);
DISPLAY INVISIBLE (-3502 2750);
FORCEADD TAP..1
(-3300 2500);
FORCEPROP 3 LASTPIN (-3350 2500) SIG_NAME M_L_CPU0_SB_DQS_DN<2>
J 0
(-3340 2510);
DISPLAY 0.659574 (-3340 2510);
PAINT MONO (-3340 2510);
DISPLAY INVISIBLE (-3340 2510);
FORCEPROP 1 LASTPIN (-3350 2500) BN 2
J 0
(-3362 2508);
DISPLAY 0.489362 (-3362 2508);
PAINT GREEN (-3362 2508);
FORCEPROP 2 LAST CDS_LIB mstr_standard
J 0
(-3300 2500);
DISPLAY 0.723404 (-3300 2500);
PAINT MONO (-3300 2500);
DISPLAY INVISIBLE (-3300 2500);
FORCEPROP 1 LAST BODY_TYPE PLUMBING
J 0
(-3300 2550);
DISPLAY 0.872340 (-3300 2550);
PAINT GREEN (-3300 2550);
DISPLAY INVISIBLE (-3300 2550);
FORCEPROP 1 LAST HDL_TAP TRUE
J 0
(-2975 2375);
DISPLAY 0.872340 (-2975 2375);
DISPLAY INVISIBLE (-2975 2375);
FORCEPROP 1 LAST PATH I228
J 0
(-3302 2500);
DISPLAY 0.872340 (-3302 2500);
PAINT GREEN (-3302 2500);
DISPLAY INVISIBLE (-3302 2500);
FORCEADD TAP..1
(-3300 2600);
FORCEPROP 3 LASTPIN (-3350 2600) SIG_NAME M_L_CPU0_SB_DQS_DN<3>
J 0
(-3340 2610);
DISPLAY 0.659574 (-3340 2610);
PAINT MONO (-3340 2610);
DISPLAY INVISIBLE (-3340 2610);
FORCEPROP 1 LASTPIN (-3350 2600) BN 3
J 0
(-3362 2608);
DISPLAY 0.489362 (-3362 2608);
PAINT GREEN (-3362 2608);
FORCEPROP 2 LAST CDS_LIB mstr_standard
J 0
(-3300 2600);
DISPLAY 0.723404 (-3300 2600);
PAINT MONO (-3300 2600);
DISPLAY INVISIBLE (-3300 2600);
FORCEPROP 1 LAST BODY_TYPE PLUMBING
J 0
(-3300 2650);
DISPLAY 0.872340 (-3300 2650);
PAINT GREEN (-3300 2650);
DISPLAY INVISIBLE (-3300 2650);
FORCEPROP 1 LAST HDL_TAP TRUE
J 0
(-2975 2475);
DISPLAY 0.872340 (-2975 2475);
DISPLAY INVISIBLE (-2975 2475);
FORCEPROP 1 LAST PATH I229
J 0
(-3302 2600);
DISPLAY 0.872340 (-3302 2600);
PAINT GREEN (-3302 2600);
DISPLAY INVISIBLE (-3302 2600);
FORCEADD TAP..1
R 2
(-7725 2875);
FORCEPROP 3 LASTPIN (-7675 2875) SIG_NAME M_L_CPU0_SB_CB<0>
J 0
(-7665 2885);
DISPLAY 0.659574 (-7665 2885);
PAINT MONO (-7665 2885);
DISPLAY INVISIBLE (-7665 2885);
FORCEPROP 1 LASTPIN (-7675 2875) BN 0
J 2
(-7663 2883);
DISPLAY 0.489362 (-7663 2883);
PAINT GREEN (-7663 2883);
FORCEPROP 2 LAST CDS_LIB mstr_standard
J 0
(-7725 2875);
DISPLAY 0.723404 (-7725 2875);
PAINT MONO (-7725 2875);
DISPLAY INVISIBLE (-7725 2875);
FORCEPROP 1 LAST BODY_TYPE PLUMBING
J 2
(-7725 2925);
DISPLAY 0.872340 (-7725 2925);
PAINT GREEN (-7725 2925);
DISPLAY INVISIBLE (-7725 2925);
FORCEPROP 1 LAST HDL_TAP TRUE
J 2
(-8050 2750);
DISPLAY 0.872340 (-8050 2750);
DISPLAY INVISIBLE (-8050 2750);
FORCEPROP 1 LAST PATH I23
J 2
(-7723 2875);
DISPLAY 0.872340 (-7723 2875);
PAINT GREEN (-7723 2875);
DISPLAY INVISIBLE (-7723 2875);
FORCEADD TAP..1
(-3300 2400);
FORCEPROP 3 LASTPIN (-3350 2400) SIG_NAME M_L_CPU0_SB_DQS_DN<1>
J 0
(-3340 2410);
DISPLAY 0.659574 (-3340 2410);
PAINT MONO (-3340 2410);
DISPLAY INVISIBLE (-3340 2410);
FORCEPROP 1 LASTPIN (-3350 2400) BN 1
J 0
(-3362 2408);
DISPLAY 0.489362 (-3362 2408);
PAINT GREEN (-3362 2408);
FORCEPROP 2 LAST CDS_LIB mstr_standard
J 0
(-3300 2400);
DISPLAY 0.723404 (-3300 2400);
PAINT MONO (-3300 2400);
DISPLAY INVISIBLE (-3300 2400);
FORCEPROP 1 LAST BODY_TYPE PLUMBING
J 0
(-3300 2450);
DISPLAY 0.872340 (-3300 2450);
PAINT GREEN (-3300 2450);
DISPLAY INVISIBLE (-3300 2450);
FORCEPROP 1 LAST HDL_TAP TRUE
J 0
(-2975 2275);
DISPLAY 0.872340 (-2975 2275);
DISPLAY INVISIBLE (-2975 2275);
FORCEPROP 1 LAST PATH I230
J 0
(-3302 2400);
DISPLAY 0.872340 (-3302 2400);
PAINT GREEN (-3302 2400);
DISPLAY INVISIBLE (-3302 2400);
FORCEADD TAP..1
(-3500 2650);
FORCEPROP 3 LASTPIN (-3550 2650) SIG_NAME M_L_CPU0_SB_DQS_DP<3>
J 0
(-3540 2660);
DISPLAY 0.659574 (-3540 2660);
PAINT MONO (-3540 2660);
DISPLAY INVISIBLE (-3540 2660);
FORCEPROP 1 LASTPIN (-3550 2650) BN 3
J 0
(-3562 2658);
DISPLAY 0.489362 (-3562 2658);
PAINT GREEN (-3562 2658);
FORCEPROP 2 LAST CDS_LIB mstr_standard
J 0
(-3500 2650);
DISPLAY 0.723404 (-3500 2650);
PAINT MONO (-3500 2650);
DISPLAY INVISIBLE (-3500 2650);
FORCEPROP 1 LAST BODY_TYPE PLUMBING
J 0
(-3500 2700);
DISPLAY 0.872340 (-3500 2700);
PAINT GREEN (-3500 2700);
DISPLAY INVISIBLE (-3500 2700);
FORCEPROP 1 LAST HDL_TAP TRUE
J 0
(-3175 2525);
DISPLAY 0.872340 (-3175 2525);
DISPLAY INVISIBLE (-3175 2525);
FORCEPROP 1 LAST PATH I231
J 0
(-3502 2650);
DISPLAY 0.872340 (-3502 2650);
PAINT GREEN (-3502 2650);
DISPLAY INVISIBLE (-3502 2650);
FORCEADD TAP..1
(-3500 2550);
FORCEPROP 3 LASTPIN (-3550 2550) SIG_NAME M_L_CPU0_SB_DQS_DP<2>
J 0
(-3540 2560);
DISPLAY 0.659574 (-3540 2560);
PAINT MONO (-3540 2560);
DISPLAY INVISIBLE (-3540 2560);
FORCEPROP 1 LASTPIN (-3550 2550) BN 2
J 0
(-3562 2558);
DISPLAY 0.489362 (-3562 2558);
PAINT GREEN (-3562 2558);
FORCEPROP 2 LAST CDS_LIB mstr_standard
J 0
(-3500 2550);
DISPLAY 0.723404 (-3500 2550);
PAINT MONO (-3500 2550);
DISPLAY INVISIBLE (-3500 2550);
FORCEPROP 1 LAST BODY_TYPE PLUMBING
J 0
(-3500 2600);
DISPLAY 0.872340 (-3500 2600);
PAINT GREEN (-3500 2600);
DISPLAY INVISIBLE (-3500 2600);
FORCEPROP 1 LAST HDL_TAP TRUE
J 0
(-3175 2425);
DISPLAY 0.872340 (-3175 2425);
DISPLAY INVISIBLE (-3175 2425);
FORCEPROP 1 LAST PATH I232
J 0
(-3502 2550);
DISPLAY 0.872340 (-3502 2550);
PAINT GREEN (-3502 2550);
DISPLAY INVISIBLE (-3502 2550);
FORCEADD TAP..1
(-3500 2450);
FORCEPROP 3 LASTPIN (-3550 2450) SIG_NAME M_L_CPU0_SB_DQS_DP<1>
J 0
(-3540 2460);
DISPLAY 0.659574 (-3540 2460);
PAINT MONO (-3540 2460);
DISPLAY INVISIBLE (-3540 2460);
FORCEPROP 1 LASTPIN (-3550 2450) BN 1
J 0
(-3562 2458);
DISPLAY 0.489362 (-3562 2458);
PAINT GREEN (-3562 2458);
FORCEPROP 2 LAST CDS_LIB mstr_standard
J 0
(-3500 2450);
DISPLAY 0.723404 (-3500 2450);
PAINT MONO (-3500 2450);
DISPLAY INVISIBLE (-3500 2450);
FORCEPROP 1 LAST BODY_TYPE PLUMBING
J 0
(-3500 2500);
DISPLAY 0.872340 (-3500 2500);
PAINT GREEN (-3500 2500);
DISPLAY INVISIBLE (-3500 2500);
FORCEPROP 1 LAST HDL_TAP TRUE
J 0
(-3175 2325);
DISPLAY 0.872340 (-3175 2325);
DISPLAY INVISIBLE (-3175 2325);
FORCEPROP 1 LAST PATH I233
J 0
(-3502 2450);
DISPLAY 0.872340 (-3502 2450);
PAINT GREEN (-3502 2450);
DISPLAY INVISIBLE (-3502 2450);
FORCEADD TAP..1
(-3300 2300);
FORCEPROP 3 LASTPIN (-3350 2300) SIG_NAME M_L_CPU0_SB_DQS_DN<0>
J 0
(-3340 2310);
DISPLAY 0.659574 (-3340 2310);
PAINT MONO (-3340 2310);
DISPLAY INVISIBLE (-3340 2310);
FORCEPROP 1 LASTPIN (-3350 2300) BN 0
J 0
(-3362 2308);
DISPLAY 0.489362 (-3362 2308);
PAINT GREEN (-3362 2308);
FORCEPROP 2 LAST CDS_LIB mstr_standard
J 0
(-3300 2300);
DISPLAY 0.723404 (-3300 2300);
PAINT MONO (-3300 2300);
DISPLAY INVISIBLE (-3300 2300);
FORCEPROP 1 LAST BODY_TYPE PLUMBING
J 0
(-3300 2350);
DISPLAY 0.872340 (-3300 2350);
PAINT GREEN (-3300 2350);
DISPLAY INVISIBLE (-3300 2350);
FORCEPROP 1 LAST HDL_TAP TRUE
J 0
(-2975 2175);
DISPLAY 0.872340 (-2975 2175);
DISPLAY INVISIBLE (-2975 2175);
FORCEPROP 1 LAST PATH I234
J 0
(-3302 2300);
DISPLAY 0.872340 (-3302 2300);
PAINT GREEN (-3302 2300);
DISPLAY INVISIBLE (-3302 2300);
FORCEADD TAP..1
(-3500 2350);
FORCEPROP 3 LASTPIN (-3550 2350) SIG_NAME M_L_CPU0_SB_DQS_DP<0>
J 0
(-3540 2360);
DISPLAY 0.659574 (-3540 2360);
PAINT MONO (-3540 2360);
DISPLAY INVISIBLE (-3540 2360);
FORCEPROP 1 LASTPIN (-3550 2350) BN 0
J 0
(-3562 2358);
DISPLAY 0.489362 (-3562 2358);
PAINT GREEN (-3562 2358);
FORCEPROP 2 LAST CDS_LIB mstr_standard
J 0
(-3500 2350);
DISPLAY 0.723404 (-3500 2350);
PAINT MONO (-3500 2350);
DISPLAY INVISIBLE (-3500 2350);
FORCEPROP 1 LAST BODY_TYPE PLUMBING
J 0
(-3500 2400);
DISPLAY 0.872340 (-3500 2400);
PAINT GREEN (-3500 2400);
DISPLAY INVISIBLE (-3500 2400);
FORCEPROP 1 LAST HDL_TAP TRUE
J 0
(-3175 2225);
DISPLAY 0.872340 (-3175 2225);
DISPLAY INVISIBLE (-3175 2225);
FORCEPROP 1 LAST PATH I235
J 0
(-3502 2350);
DISPLAY 0.872340 (-3502 2350);
PAINT GREEN (-3502 2350);
DISPLAY INVISIBLE (-3502 2350);
FORCEADD SCONN288_DDR506112002KQ..2
(-4450 3300);
FORCEPROP 1 LAST LOCATION J67
J 0
(-5050 4625);
DISPLAY 0.468085 (-5050 4625);
PAINT SKYBLUE (-5050 4625);
FORCEPROP 0 LAST $SEC 2
J 0
(-4900 4775);
DISPLAY 0.680851 (-4900 4775);
PAINT MONO (-4900 4775);
DISPLAY INVISIBLE (-4900 4775);
FORCEPROP 0 LAST CDS_SEC 2
J 0
(-4900 4775);
DISPLAY 1.021277 (-4900 4775);
DISPLAY INVISIBLE (-4900 4775);
FORCEPROP 0 LASTPIN (-3700 3350) $PN 12
J 0
(-3690 3360);
DISPLAY 0.680851 (-3690 3360);
PAINT MONO (-3690 3360);
FORCEPROP 0 LASTPIN (-3700 3400) $PN 11
J 0
(-3690 3410);
DISPLAY 0.680851 (-3690 3410);
PAINT MONO (-3690 3410);
FORCEPROP 0 LASTPIN (-3700 2300) $PN 105
J 0
(-3690 2310);
DISPLAY 0.680851 (-3690 2310);
PAINT MONO (-3690 2310);
FORCEPROP 0 LASTPIN (-3700 2350) $PN 104
J 0
(-3690 2360);
DISPLAY 0.680851 (-3690 2360);
PAINT MONO (-3690 2360);
FORCEPROP 0 LASTPIN (-3700 3450) $PN 23
J 0
(-3690 3460);
DISPLAY 0.680851 (-3690 3460);
PAINT MONO (-3690 3460);
FORCEPROP 0 LASTPIN (-3700 3500) $PN 22
J 0
(-3690 3510);
DISPLAY 0.680851 (-3690 3510);
PAINT MONO (-3690 3510);
FORCEPROP 0 LASTPIN (-3700 2400) $PN 116
J 0
(-3690 2410);
DISPLAY 0.680851 (-3690 2410);
PAINT MONO (-3690 2410);
FORCEPROP 0 LASTPIN (-3700 2450) $PN 115
J 0
(-3690 2460);
DISPLAY 0.680851 (-3690 2460);
PAINT MONO (-3690 2460);
FORCEPROP 0 LASTPIN (-3700 3550) $PN 34
J 0
(-3690 3560);
DISPLAY 0.680851 (-3690 3560);
PAINT MONO (-3690 3560);
FORCEPROP 0 LASTPIN (-3700 3600) $PN 33
J 0
(-3690 3610);
DISPLAY 0.680851 (-3690 3610);
PAINT MONO (-3690 3610);
FORCEPROP 0 LASTPIN (-3700 2500) $PN 127
J 0
(-3690 2510);
DISPLAY 0.680851 (-3690 2510);
PAINT MONO (-3690 2510);
FORCEPROP 0 LASTPIN (-3700 2550) $PN 126
J 0
(-3690 2560);
DISPLAY 0.680851 (-3690 2560);
PAINT MONO (-3690 2560);
FORCEPROP 0 LASTPIN (-3700 3650) $PN 45
J 0
(-3690 3660);
DISPLAY 0.680851 (-3690 3660);
PAINT MONO (-3690 3660);
FORCEPROP 0 LASTPIN (-3700 3700) $PN 44
J 0
(-3690 3710);
DISPLAY 0.680851 (-3690 3710);
PAINT MONO (-3690 3710);
FORCEPROP 0 LASTPIN (-3700 2600) $PN 138
J 0
(-3690 2610);
DISPLAY 0.680851 (-3690 2610);
PAINT MONO (-3690 2610);
FORCEPROP 0 LASTPIN (-3700 2650) $PN 137
J 0
(-3690 2660);
DISPLAY 0.680851 (-3690 2660);
PAINT MONO (-3690 2660);
FORCEPROP 0 LASTPIN (-3700 3750) $PN 56
J 0
(-3690 3760);
DISPLAY 0.680851 (-3690 3760);
PAINT MONO (-3690 3760);
FORCEPROP 0 LASTPIN (-3700 3800) $PN 55
J 0
(-3690 3810);
DISPLAY 0.680851 (-3690 3810);
PAINT MONO (-3690 3810);
FORCEPROP 0 LASTPIN (-3700 2700) $PN 238
J 0
(-3690 2710);
DISPLAY 0.680851 (-3690 2710);
PAINT MONO (-3690 2710);
FORCEPROP 0 LASTPIN (-3700 2750) $PN 239
J 0
(-3690 2760);
DISPLAY 0.680851 (-3690 2760);
PAINT MONO (-3690 2760);
FORCEPROP 0 LASTPIN (-3700 3850) $PN 156
J 0
(-3690 3860);
DISPLAY 0.680851 (-3690 3860);
PAINT MONO (-3690 3860);
FORCEPROP 0 LASTPIN (-3700 3900) $PN 157
J 0
(-3690 3910);
DISPLAY 0.680851 (-3690 3910);
PAINT MONO (-3690 3910);
FORCEPROP 0 LASTPIN (-3700 2800) $PN 249
J 0
(-3690 2810);
DISPLAY 0.680851 (-3690 2810);
PAINT MONO (-3690 2810);
FORCEPROP 0 LASTPIN (-3700 2850) $PN 250
J 0
(-3690 2860);
DISPLAY 0.680851 (-3690 2860);
PAINT MONO (-3690 2860);
FORCEPROP 0 LASTPIN (-3700 3950) $PN 167
J 0
(-3690 3960);
DISPLAY 0.680851 (-3690 3960);
PAINT MONO (-3690 3960);
FORCEPROP 0 LASTPIN (-3700 4000) $PN 168
J 0
(-3690 4010);
DISPLAY 0.680851 (-3690 4010);
PAINT MONO (-3690 4010);
FORCEPROP 0 LASTPIN (-3700 2900) $PN 260
J 0
(-3690 2910);
DISPLAY 0.680851 (-3690 2910);
PAINT MONO (-3690 2910);
FORCEPROP 0 LASTPIN (-3700 2950) $PN 261
J 0
(-3690 2960);
DISPLAY 0.680851 (-3690 2960);
PAINT MONO (-3690 2960);
FORCEPROP 0 LASTPIN (-3700 4050) $PN 178
J 0
(-3690 4060);
DISPLAY 0.680851 (-3690 4060);
PAINT MONO (-3690 4060);
FORCEPROP 0 LASTPIN (-3700 4100) $PN 179
J 0
(-3690 4110);
DISPLAY 0.680851 (-3690 4110);
PAINT MONO (-3690 4110);
FORCEPROP 0 LASTPIN (-3700 3000) $PN 271
J 0
(-3690 3010);
DISPLAY 0.680851 (-3690 3010);
PAINT MONO (-3690 3010);
FORCEPROP 0 LASTPIN (-3700 3050) $PN 272
J 0
(-3690 3060);
DISPLAY 0.680851 (-3690 3060);
PAINT MONO (-3690 3060);
FORCEPROP 0 LASTPIN (-3700 4150) $PN 189
J 0
(-3690 4160);
DISPLAY 0.680851 (-3690 4160);
PAINT MONO (-3690 4160);
FORCEPROP 0 LASTPIN (-3700 4200) $PN 190
J 0
(-3690 4210);
DISPLAY 0.680851 (-3690 4210);
PAINT MONO (-3690 4210);
FORCEPROP 0 LASTPIN (-3700 3100) $PN 282
J 0
(-3690 3110);
DISPLAY 0.680851 (-3690 3110);
PAINT MONO (-3690 3110);
FORCEPROP 0 LASTPIN (-3700 3150) $PN 283
J 0
(-3690 3160);
DISPLAY 0.680851 (-3690 3160);
PAINT MONO (-3690 3160);
FORCEPROP 0 LASTPIN (-3700 4250) $PN 200
J 0
(-3690 4260);
DISPLAY 0.680851 (-3690 4260);
PAINT MONO (-3690 4260);
FORCEPROP 0 LASTPIN (-3700 4300) $PN 201
J 0
(-3690 4310);
DISPLAY 0.680851 (-3690 4310);
PAINT MONO (-3690 4310);
FORCEPROP 0 LASTPIN (-3700 3200) $PN 94
J 0
(-3690 3210);
DISPLAY 0.680851 (-3690 3210);
PAINT MONO (-3690 3210);
FORCEPROP 0 LASTPIN (-3700 3250) $PN 93
J 0
(-3690 3260);
DISPLAY 0.680851 (-3690 3260);
PAINT MONO (-3690 3260);
FORCEPROP 2 LAST PART_TYPE SMLF
J 0
(-4900 4725);
DISPLAY 1.021277 (-4900 4725);
FORCEPROP 2 LAST VALUE SCONN288_DDR506112002KQ
J 0
(-4900 4675);
DISPLAY 0.489362 (-4900 4675);
PAINT SKYBLUE (-4900 4675);
FORCEPROP 1 LAST MATERIAL IO
J 0
(-5050 4475);
DISPLAY 0.468085 (-5050 4475);
PAINT SKYBLUE (-5050 4475);
FORCEPROP 1 LAST CDS_LMAN_SYM_OUTLINE -600,1150,600,-1150
J 0
(-4450 3300);
DISPLAY 0.468085 (-4450 3300);
PAINT GREEN (-4450 3300);
DISPLAY INVISIBLE (-4450 3300);
FORCEPROP 1 LAST NEEDS_NO_SIZE TRUE
J 0
(-4450 3300);
DISPLAY 0.723404 (-4450 3300);
PAINT GREEN (-4450 3300);
DISPLAY INVISIBLE (-4450 3300);
FORCEPROP 2 LAST CDS_LIB pure_quanta
J 0
(-4450 3300);
DISPLAY INVISIBLE (-4450 3300);
FORCEPROP 1 LAST PATH I236
J 0
(-4450 3300);
DISPLAY 0.723404 (-4450 3300);
PAINT GREEN (-4450 3300);
DISPLAY INVISIBLE (-4450 3300);
FORCEPROP 1 LAST PART_NUMBER DFHST8FS479
J 0
(-5050 4550);
DISPLAY 0.468085 (-5050 4550);
PAINT SKYBLUE (-5050 4550);
DISPLAY INVISIBLE (-5050 4550);
FORCEADD GND..1
(-2900 5250);
FORCEPROP 3 LASTPIN (-2900 5300) SIG_NAME GND\g
J 0
(-2890 5310);
DISPLAY 0.659574 (-2890 5310);
PAINT MONO (-2890 5310);
DISPLAY INVISIBLE (-2890 5310);
FORCEPROP 1 LAST SIZE 1B
J 0
(-2825 5200);
DISPLAY 0.723404 (-2825 5200);
PAINT GREEN (-2825 5200);
DISPLAY INVISIBLE (-2825 5200);
FORCEPROP 2 LAST BOM_COST MEM
J 0
(-2875 5375);
DISPLAY 0.659574 (-2875 5375);
DISPLAY INVISIBLE (-2875 5375);
FORCEPROP 2 LAST CDS_LIB pure_quanta_power
J 0
(-2900 5250);
DISPLAY INVISIBLE (-2900 5250);
FORCEPROP 2 LAST ROOM MEM_EFGH_DECOUPLING_CAPS
J 0
(-2875 5325);
DISPLAY 0.659574 (-2875 5325);
PAINT RED (-2875 5325);
DISPLAY INVISIBLE (-2875 5325);
FORCEPROP 1 LAST HDL_POWER GND
J 0
(-2900 5400);
DISPLAY 0.723404 (-2900 5400);
PAINT GREEN (-2900 5400);
DISPLAY INVISIBLE (-2900 5400);
FORCEPROP 1 LAST PATH I237
J 0
(-2825 5250);
DISPLAY 0.872340 (-2825 5250);
PAINT AQUA (-2825 5250);
DISPLAY INVISIBLE (-2825 5250);
FORCEADD Q_CAP..1
R 2
(-2900 5600);
FORCEPROP 1 LAST LOCATION C170
J 2
(-2950 5700);
DISPLAY 0.489362 (-2950 5700);
PAINT SKYBLUE (-2950 5700);
FORCEPROP 0 LAST $SEC 1
J 0
(-2950 5750);
DISPLAY 0.680851 (-2950 5750);
PAINT MONO (-2950 5750);
DISPLAY INVISIBLE (-2950 5750);
FORCEPROP 0 LAST CDS_SEC 1
J 0
(-2950 5750);
DISPLAY 0.680851 (-2950 5750);
DISPLAY INVISIBLE (-2950 5750);
FORCEPROP 1 LASTPIN (-2900 5700) $PN 1
J 2
(-2910 5680);
DISPLAY 0.489362 (-2910 5680);
PAINT MONO (-2910 5680);
FORCEPROP 1 LASTPIN (-2900 5500) $PN 2
J 2
(-2910 5480);
DISPLAY 0.489362 (-2910 5480);
PAINT MONO (-2910 5480);
FORCEPROP 1 LAST TOLERANCE 10%
J 2
(-2950 5550);
DISPLAY 0.489362 (-2950 5550);
PAINT SKYBLUE (-2950 5550);
FORCEPROP 1 LAST MATERIAL X6S
J 2
(-2950 5500);
DISPLAY 0.489362 (-2950 5500);
PAINT SKYBLUE (-2950 5500);
FORCEPROP 1 LAST PACK_TYPE C0805
J 2
(-2950 5400);
DISPLAY 0.489362 (-2950 5400);
PAINT SKYBLUE (-2950 5400);
FORCEPROP 1 LAST VOLTAGE 25V
J 2
(-2950 5600);
DISPLAY 0.489362 (-2950 5600);
PAINT SKYBLUE (-2950 5600);
FORCEPROP 1 LAST VALUE 10UF
J 2
(-2950 5650);
DISPLAY 0.489362 (-2950 5650);
PAINT SKYBLUE (-2950 5650);
FORCEPROP 0 LAST BOM_COST MEM
J 2
(-2955 5745);
DISPLAY 0.595745 (-2955 5745);
PAINT MONO (-2955 5745);
DISPLAY INVISIBLE (-2955 5745);
FORCEPROP 2 LAST CDS_LIB pure_quanta
J 0
(-2900 5600);
DISPLAY INVISIBLE (-2900 5600);
FORCEPROP 2 LAST ROOM 
J 2
(-2955 5745);
DISPLAY 0.595745 (-2955 5745);
PAINT RED (-2955 5745);
DISPLAY INVISIBLE (-2955 5745);
FORCEPROP 1 LAST PATH I238
J 2
(-2950 5750);
DISPLAY 0.978723 (-2950 5750);
PAINT WHITE (-2950 5750);
DISPLAY INVISIBLE (-2950 5750);
FORCEPROP 1 LAST PART_NUMBER CH6104KEA00
J 2
(-2950 5450);
DISPLAY 0.489362 (-2950 5450);
PAINT SKYBLUE (-2950 5450);
DISPLAY INVISIBLE (-2950 5450);
FORCEADD Q_CAP..1
R 2
(-2325 5600);
FORCEPROP 1 LAST LOCATION C171
J 2
(-2375 5700);
DISPLAY 0.489362 (-2375 5700);
PAINT SKYBLUE (-2375 5700);
FORCEPROP 0 LAST $SEC 1
J 0
(-2375 5750);
DISPLAY 0.680851 (-2375 5750);
PAINT MONO (-2375 5750);
DISPLAY INVISIBLE (-2375 5750);
FORCEPROP 0 LAST CDS_SEC 1
J 0
(-2375 5750);
DISPLAY 0.680851 (-2375 5750);
DISPLAY INVISIBLE (-2375 5750);
FORCEPROP 1 LASTPIN (-2325 5700) $PN 1
J 2
(-2335 5680);
DISPLAY 0.489362 (-2335 5680);
PAINT MONO (-2335 5680);
FORCEPROP 1 LASTPIN (-2325 5500) $PN 2
J 2
(-2335 5480);
DISPLAY 0.489362 (-2335 5480);
PAINT MONO (-2335 5480);
FORCEPROP 1 LAST MATERIAL X6S
J 2
(-2375 5500);
DISPLAY 0.489362 (-2375 5500);
PAINT SKYBLUE (-2375 5500);
FORCEPROP 1 LAST PACK_TYPE C0805
J 2
(-2375 5400);
DISPLAY 0.489362 (-2375 5400);
PAINT SKYBLUE (-2375 5400);
FORCEPROP 1 LAST VOLTAGE 25V
J 2
(-2375 5600);
DISPLAY 0.489362 (-2375 5600);
PAINT SKYBLUE (-2375 5600);
FORCEPROP 1 LAST VALUE 10UF
J 2
(-2375 5650);
DISPLAY 0.489362 (-2375 5650);
PAINT SKYBLUE (-2375 5650);
FORCEPROP 1 LAST TOLERANCE 10%
J 2
(-2375 5550);
DISPLAY 0.489362 (-2375 5550);
PAINT SKYBLUE (-2375 5550);
FORCEPROP 0 LAST BOM_COST MEM
J 2
(-2380 5745);
DISPLAY 0.595745 (-2380 5745);
PAINT MONO (-2380 5745);
DISPLAY INVISIBLE (-2380 5745);
FORCEPROP 2 LAST CDS_LIB pure_quanta
J 0
(-2325 5600);
DISPLAY INVISIBLE (-2325 5600);
FORCEPROP 2 LAST ROOM 
J 2
(-2380 5745);
DISPLAY 0.595745 (-2380 5745);
PAINT RED (-2380 5745);
DISPLAY INVISIBLE (-2380 5745);
FORCEPROP 1 LAST PATH I239
J 2
(-2375 5750);
DISPLAY 0.978723 (-2375 5750);
PAINT WHITE (-2375 5750);
DISPLAY INVISIBLE (-2375 5750);
FORCEPROP 1 LAST PART_NUMBER CH6104KEA00
J 2
(-2375 5450);
DISPLAY 0.489362 (-2375 5450);
PAINT SKYBLUE (-2375 5450);
DISPLAY INVISIBLE (-2375 5450);
FORCEADD TAP..1
R 2
(-7725 2925);
FORCEPROP 3 LASTPIN (-7675 2925) SIG_NAME M_L_CPU0_SB_CB<1>
J 0
(-7665 2935);
DISPLAY 0.659574 (-7665 2935);
PAINT MONO (-7665 2935);
DISPLAY INVISIBLE (-7665 2935);
FORCEPROP 1 LASTPIN (-7675 2925) BN 1
J 2
(-7663 2933);
DISPLAY 0.489362 (-7663 2933);
PAINT GREEN (-7663 2933);
FORCEPROP 2 LAST CDS_LIB mstr_standard
J 0
(-7725 2925);
DISPLAY 0.723404 (-7725 2925);
PAINT MONO (-7725 2925);
DISPLAY INVISIBLE (-7725 2925);
FORCEPROP 1 LAST BODY_TYPE PLUMBING
J 2
(-7725 2975);
DISPLAY 0.872340 (-7725 2975);
PAINT GREEN (-7725 2975);
DISPLAY INVISIBLE (-7725 2975);
FORCEPROP 1 LAST HDL_TAP TRUE
J 2
(-8050 2800);
DISPLAY 0.872340 (-8050 2800);
DISPLAY INVISIBLE (-8050 2800);
FORCEPROP 1 LAST PATH I24
J 2
(-7723 2925);
DISPLAY 0.872340 (-7723 2925);
PAINT GREEN (-7723 2925);
DISPLAY INVISIBLE (-7723 2925);
FORCEADD UNIVERSAL_POWER..1
(-2900 5925);
FORCEPROP 3 LASTPIN (-2900 5875) SIG_NAME P12V_MEM_CPU0\g
J 0
(-2890 5885);
DISPLAY 0.659574 (-2890 5885);
PAINT MONO (-2890 5885);
DISPLAY INVISIBLE (-2890 5885);
FORCEPROP 1 LAST HDL_POWER P12V_MEM_CPU0
J 1
(-2925 5975);
DISPLAY 0.489362 (-2925 5975);
PAINT GREEN (-2925 5975);
FORCEPROP 2 LAST CDS_LIB pure_quanta_power
J 0
(-2900 5925);
DISPLAY INVISIBLE (-2900 5925);
FORCEPROP 2 LAST BOM_COST VR_SYSTEM
J 0
(-2900 6025);
DISPLAY 0.617021 (-2900 6025);
PAINT PURPLE (-2900 6025);
DISPLAY INVISIBLE (-2900 6025);
FORCEPROP 1 LAST PATH I240
J 0
(-2850 5950);
DISPLAY 0.872340 (-2850 5950);
PAINT AQUA (-2850 5950);
DISPLAY INVISIBLE (-2850 5950);
FORCEADD OFFPAGE..1
(-8425 2300);
FORCEPROP 2 LAST $XR5 96 
J 0
(-9127 2300);
DISPLAY 0.638298 (-9127 2300);
PAINT MONO (-9127 2300);
FORCEPROP 2 LAST $XR4 95 
J 0
(-9037 2300);
DISPLAY 0.638298 (-9037 2300);
PAINT MONO (-9037 2300);
FORCEPROP 2 LAST $XR3 94 
J 0
(-8947 2300);
DISPLAY 0.638298 (-8947 2300);
PAINT MONO (-8947 2300);
FORCEPROP 2 LAST $XR2 93 
J 0
(-8857 2300);
DISPLAY 0.638298 (-8857 2300);
PAINT MONO (-8857 2300);
FORCEPROP 2 LAST $XR1 92 
J 0
(-8767 2300);
DISPLAY 0.638298 (-8767 2300);
PAINT MONO (-8767 2300);
FORCEPROP 2 LAST $XR0 159 
J 0
(-8677 2300);
DISPLAY 0.638298 (-8677 2300);
PAINT MONO (-8677 2300);
FORCEPROP 2 LAST CDS_LIB mstr_standard
J 0
(-8425 2300);
DISPLAY 0.808511 (-8425 2300);
DISPLAY INVISIBLE (-8425 2300);
FORCEPROP 1 LAST OFFPAGE TRUE
J 0
(-8100 2175);
DISPLAY 0.872340 (-8100 2175);
PAINT GREEN (-8100 2175);
DISPLAY INVISIBLE (-8100 2175);
FORCEPROP 1 LAST COMMENT_BODY TRUE
J 0
(-8300 2200);
DISPLAY 0.872340 (-8300 2200);
PAINT GREEN (-8300 2200);
DISPLAY INVISIBLE (-8300 2200);
FORCEPROP 2 LAST PATH I241
J 0
(-8700 2350);
DISPLAY 0.680851 (-8700 2350);
DISPLAY INVISIBLE (-8700 2350);
FORCEADD Q_RES..1
(-7775 2300);
FORCEPROP 1 LAST LOCATION R1579
J 0
(-7825 2325);
DISPLAY 0.638298 (-7825 2325);
PAINT SKYBLUE (-7825 2325);
FORCEPROP 0 LAST $SEC 1
J 0
(-7825 2400);
DISPLAY 0.680851 (-7825 2400);
PAINT MONO (-7825 2400);
DISPLAY INVISIBLE (-7825 2400);
FORCEPROP 0 LAST CDS_SEC 1
J 0
(-7825 2400);
DISPLAY 0.680851 (-7825 2400);
DISPLAY INVISIBLE (-7825 2400);
FORCEPROP 1 LASTPIN (-7875 2300) $PN 1
J 0
(-7863 2312);
DISPLAY 0.787234 (-7863 2312);
PAINT MONO (-7863 2312);
FORCEPROP 1 LASTPIN (-7675 2300) $PN 2
J 0
(-7713 2312);
DISPLAY 0.787234 (-7713 2312);
PAINT MONO (-7713 2312);
FORCEPROP 1 LAST VALUE 49.9
J 2
(-7600 2350);
DISPLAY 0.510638 (-7600 2350);
PAINT SKYBLUE (-7600 2350);
FORCEPROP 2 LAST CDS_LIB pure_quanta
J 0
(-7775 2300);
DISPLAY INVISIBLE (-7775 2300);
FORCEPROP 1 LAST MATERIAL CHIP
J 0
(-7775 2150);
DISPLAY 0.978723 (-7775 2150);
DISPLAY INVISIBLE (-7775 2150);
FORCEPROP 1 LAST PACK_TYPE 0402LF
J 0
(-7525 2150);
DISPLAY 0.978723 (-7525 2150);
DISPLAY INVISIBLE (-7525 2150);
FORCEPROP 1 LAST WATTAGE 1/16W
J 2
(-7800 2150);
DISPLAY 0.978723 (-7800 2150);
DISPLAY INVISIBLE (-7800 2150);
FORCEPROP 1 LAST TOLERANCE 1%
J 0
(-7775 2200);
DISPLAY 0.978723 (-7775 2200);
DISPLAY INVISIBLE (-7775 2200);
FORCEPROP 1 LAST PATH I242
J 0
(-7825 2450);
DISPLAY 0.978723 (-7825 2450);
PAINT WHITE (-7825 2450);
DISPLAY INVISIBLE (-7825 2450);
FORCEPROP 1 LAST PART_NUMBER CS04992FB07
J 0
(-7825 2400);
DISPLAY 0.978723 (-7825 2400);
DISPLAY INVISIBLE (-7825 2400);
FORCEADD Q_RES..1
(-8125 2525);
FORCEPROP 1 LAST LOCATION R1686
J 0
(-8325 2525);
DISPLAY 0.638298 (-8325 2525);
FORCEPROP 0 LAST $SEC 1
J 0
(-8275 2575);
DISPLAY 0.680851 (-8275 2575);
PAINT MONO (-8275 2575);
DISPLAY INVISIBLE (-8275 2575);
FORCEPROP 0 LAST CDS_SEC 1
J 0
(-8275 2575);
DISPLAY 0.680851 (-8275 2575);
DISPLAY INVISIBLE (-8275 2575);
FORCEPROP 1 LASTPIN (-8225 2525) $PN 1
J 0
(-8213 2537);
DISPLAY 0.787234 (-8213 2537);
PAINT MONO (-8213 2537);
FORCEPROP 1 LASTPIN (-8025 2525) $PN 2
J 0
(-8063 2537);
DISPLAY 0.787234 (-8063 2537);
PAINT MONO (-8063 2537);
FORCEPROP 1 LAST PACK_TYPE 0402LF
J 0
(-8075 2500);
DISPLAY 0.404255 (-8075 2500);
FORCEPROP 1 LAST VALUE 10
J 2
(-7975 2525);
DISPLAY 0.404255 (-7975 2525);
FORCEPROP 1 LAST MATERIAL CHIP
J 0
(-8225 2500);
DISPLAY 0.404255 (-8225 2500);
FORCEPROP 2 LAST CDS_LIB pure_quanta
J 0
(-8125 2525);
DISPLAY INVISIBLE (-8125 2525);
FORCEPROP 1 LAST TOLERANCE 1%
J 0
(-8125 2425);
DISPLAY 0.978723 (-8125 2425);
DISPLAY INVISIBLE (-8125 2425);
FORCEPROP 1 LAST WATTAGE 1/16W
J 2
(-8150 2375);
DISPLAY 0.978723 (-8150 2375);
DISPLAY INVISIBLE (-8150 2375);
FORCEPROP 1 LAST PATH I243
J 0
(-8175 2675);
DISPLAY 0.978723 (-8175 2675);
PAINT WHITE (-8175 2675);
DISPLAY INVISIBLE (-8175 2675);
FORCEPROP 1 LAST PART_NUMBER CS01002FB07
J 0
(-8175 2625);
DISPLAY 0.978723 (-8175 2625);
DISPLAY INVISIBLE (-8175 2625);
FORCEADD OFFPAGE..6
(-8775 2425);
FORCEPROP 2 LAST $XR5 159 
J 0
(-9144 2389);
DISPLAY 0.638298 (-9144 2389);
PAINT MONO (-9144 2389);
FORCEPROP 2 LAST $XR4 96 
J 0
(-9024 2389);
DISPLAY 0.638298 (-9024 2389);
PAINT MONO (-9024 2389);
FORCEPROP 2 LAST $XR3 95 
J 0
(-9294 2425);
DISPLAY 0.638298 (-9294 2425);
PAINT MONO (-9294 2425);
FORCEPROP 2 LAST $XR2 94 
J 0
(-9204 2425);
DISPLAY 0.638298 (-9204 2425);
PAINT MONO (-9204 2425);
FORCEPROP 2 LAST $XR1 93 
J 0
(-9114 2425);
DISPLAY 0.638298 (-9114 2425);
PAINT MONO (-9114 2425);
FORCEPROP 2 LAST $XR0 92 
J 0
(-9024 2425);
DISPLAY 0.638298 (-9024 2425);
PAINT MONO (-9024 2425);
FORCEPROP 2 LAST CDS_LIB mstr_standard
J 0
(-8775 2425);
DISPLAY 0.808511 (-8775 2425);
DISPLAY INVISIBLE (-8775 2425);
FORCEPROP 1 LAST OFFPAGE TRUE
J 0
(-8450 2300);
DISPLAY 0.872340 (-8450 2300);
PAINT GREEN (-8450 2300);
DISPLAY INVISIBLE (-8450 2300);
FORCEPROP 1 LAST COMMENT_BODY TRUE
J 0
(-8675 2350);
DISPLAY 0.872340 (-8675 2350);
PAINT GREEN (-8675 2350);
DISPLAY INVISIBLE (-8675 2350);
FORCEPROP 2 LAST PATH I244
J 0
(-9000 2475);
DISPLAY 0.680851 (-9000 2475);
DISPLAY INVISIBLE (-9000 2475);
FORCEADD TAP..1
R 2
(-7725 2975);
FORCEPROP 3 LASTPIN (-7675 2975) SIG_NAME M_L_CPU0_SB_CB<2>
J 0
(-7665 2985);
DISPLAY 0.659574 (-7665 2985);
PAINT MONO (-7665 2985);
DISPLAY INVISIBLE (-7665 2985);
FORCEPROP 1 LASTPIN (-7675 2975) BN 2
J 2
(-7663 2983);
DISPLAY 0.489362 (-7663 2983);
PAINT GREEN (-7663 2983);
FORCEPROP 2 LAST CDS_LIB mstr_standard
J 0
(-7725 2975);
DISPLAY 0.723404 (-7725 2975);
PAINT MONO (-7725 2975);
DISPLAY INVISIBLE (-7725 2975);
FORCEPROP 1 LAST BODY_TYPE PLUMBING
J 2
(-7725 3025);
DISPLAY 0.872340 (-7725 3025);
PAINT GREEN (-7725 3025);
DISPLAY INVISIBLE (-7725 3025);
FORCEPROP 1 LAST HDL_TAP TRUE
J 2
(-8050 2850);
DISPLAY 0.872340 (-8050 2850);
DISPLAY INVISIBLE (-8050 2850);
FORCEPROP 1 LAST PATH I25
J 2
(-7723 2975);
DISPLAY 0.872340 (-7723 2975);
PAINT GREEN (-7723 2975);
DISPLAY INVISIBLE (-7723 2975);
FORCEADD TAP..1
R 2
(-7725 3075);
FORCEPROP 3 LASTPIN (-7675 3075) SIG_NAME M_L_CPU0_SB_CB<4>
J 0
(-7665 3085);
DISPLAY 0.659574 (-7665 3085);
PAINT MONO (-7665 3085);
DISPLAY INVISIBLE (-7665 3085);
FORCEPROP 1 LASTPIN (-7675 3075) BN 4
J 2
(-7663 3083);
DISPLAY 0.489362 (-7663 3083);
PAINT GREEN (-7663 3083);
FORCEPROP 2 LAST CDS_LIB mstr_standard
J 0
(-7725 3075);
DISPLAY 0.723404 (-7725 3075);
PAINT MONO (-7725 3075);
DISPLAY INVISIBLE (-7725 3075);
FORCEPROP 1 LAST BODY_TYPE PLUMBING
J 2
(-7725 3125);
DISPLAY 0.872340 (-7725 3125);
PAINT GREEN (-7725 3125);
DISPLAY INVISIBLE (-7725 3125);
FORCEPROP 1 LAST HDL_TAP TRUE
J 2
(-8050 2950);
DISPLAY 0.872340 (-8050 2950);
DISPLAY INVISIBLE (-8050 2950);
FORCEPROP 1 LAST PATH I26
J 2
(-7723 3075);
DISPLAY 0.872340 (-7723 3075);
PAINT GREEN (-7723 3075);
DISPLAY INVISIBLE (-7723 3075);
FORCEADD TAP..1
R 2
(-7725 3125);
FORCEPROP 3 LASTPIN (-7675 3125) SIG_NAME M_L_CPU0_SB_CB<5>
J 0
(-7665 3135);
DISPLAY 0.659574 (-7665 3135);
PAINT MONO (-7665 3135);
DISPLAY INVISIBLE (-7665 3135);
FORCEPROP 1 LASTPIN (-7675 3125) BN 5
J 2
(-7663 3133);
DISPLAY 0.489362 (-7663 3133);
PAINT GREEN (-7663 3133);
FORCEPROP 2 LAST CDS_LIB mstr_standard
J 0
(-7725 3125);
DISPLAY 0.723404 (-7725 3125);
PAINT MONO (-7725 3125);
DISPLAY INVISIBLE (-7725 3125);
FORCEPROP 1 LAST BODY_TYPE PLUMBING
J 2
(-7725 3175);
DISPLAY 0.872340 (-7725 3175);
PAINT GREEN (-7725 3175);
DISPLAY INVISIBLE (-7725 3175);
FORCEPROP 1 LAST HDL_TAP TRUE
J 2
(-8050 3000);
DISPLAY 0.872340 (-8050 3000);
DISPLAY INVISIBLE (-8050 3000);
FORCEPROP 1 LAST PATH I27
J 2
(-7723 3125);
DISPLAY 0.872340 (-7723 3125);
PAINT GREEN (-7723 3125);
DISPLAY INVISIBLE (-7723 3125);
FORCEADD TAP..1
R 2
(-7725 3025);
FORCEPROP 3 LASTPIN (-7675 3025) SIG_NAME M_L_CPU0_SB_CB<3>
J 0
(-7665 3035);
DISPLAY 0.659574 (-7665 3035);
PAINT MONO (-7665 3035);
DISPLAY INVISIBLE (-7665 3035);
FORCEPROP 1 LASTPIN (-7675 3025) BN 3
J 2
(-7663 3033);
DISPLAY 0.489362 (-7663 3033);
PAINT GREEN (-7663 3033);
FORCEPROP 2 LAST CDS_LIB mstr_standard
J 0
(-7725 3025);
DISPLAY 0.723404 (-7725 3025);
PAINT MONO (-7725 3025);
DISPLAY INVISIBLE (-7725 3025);
FORCEPROP 1 LAST BODY_TYPE PLUMBING
J 2
(-7725 3075);
DISPLAY 0.872340 (-7725 3075);
PAINT GREEN (-7725 3075);
DISPLAY INVISIBLE (-7725 3075);
FORCEPROP 1 LAST HDL_TAP TRUE
J 2
(-8050 2900);
DISPLAY 0.872340 (-8050 2900);
DISPLAY INVISIBLE (-8050 2900);
FORCEPROP 1 LAST PATH I28
J 2
(-7723 3025);
DISPLAY 0.872340 (-7723 3025);
PAINT GREEN (-7723 3025);
DISPLAY INVISIBLE (-7723 3025);
FORCEADD TAP..1
R 2
(-7725 3225);
FORCEPROP 3 LASTPIN (-7675 3225) SIG_NAME M_L_CPU0_SB_CB<7>
J 0
(-7665 3235);
DISPLAY 0.659574 (-7665 3235);
PAINT MONO (-7665 3235);
DISPLAY INVISIBLE (-7665 3235);
FORCEPROP 1 LASTPIN (-7675 3225) BN 7
J 2
(-7663 3233);
DISPLAY 0.489362 (-7663 3233);
PAINT GREEN (-7663 3233);
FORCEPROP 2 LAST CDS_LIB mstr_standard
J 0
(-7725 3225);
DISPLAY 0.723404 (-7725 3225);
PAINT MONO (-7725 3225);
DISPLAY INVISIBLE (-7725 3225);
FORCEPROP 1 LAST BODY_TYPE PLUMBING
J 2
(-7725 3275);
DISPLAY 0.872340 (-7725 3275);
PAINT GREEN (-7725 3275);
DISPLAY INVISIBLE (-7725 3275);
FORCEPROP 1 LAST HDL_TAP TRUE
J 2
(-8050 3100);
DISPLAY 0.872340 (-8050 3100);
DISPLAY INVISIBLE (-8050 3100);
FORCEPROP 1 LAST PATH I29
J 2
(-7723 3225);
DISPLAY 0.872340 (-7723 3225);
PAINT GREEN (-7723 3225);
DISPLAY INVISIBLE (-7723 3225);
FORCEADD TAP..1
R 2
(-7725 3375);
FORCEPROP 3 LASTPIN (-7675 3375) SIG_NAME M_L_CPU0_SA_CB<1>
J 0
(-7665 3385);
DISPLAY 0.659574 (-7665 3385);
PAINT MONO (-7665 3385);
DISPLAY INVISIBLE (-7665 3385);
FORCEPROP 1 LASTPIN (-7675 3375) BN 1
J 2
(-7663 3383);
DISPLAY 0.489362 (-7663 3383);
PAINT GREEN (-7663 3383);
FORCEPROP 2 LAST CDS_LIB mstr_standard
J 0
(-7725 3375);
DISPLAY 0.723404 (-7725 3375);
PAINT MONO (-7725 3375);
DISPLAY INVISIBLE (-7725 3375);
FORCEPROP 1 LAST BODY_TYPE PLUMBING
J 2
(-7725 3425);
DISPLAY 0.872340 (-7725 3425);
PAINT GREEN (-7725 3425);
DISPLAY INVISIBLE (-7725 3425);
FORCEPROP 1 LAST HDL_TAP TRUE
J 2
(-8050 3250);
DISPLAY 0.872340 (-8050 3250);
DISPLAY INVISIBLE (-8050 3250);
FORCEPROP 1 LAST PATH I30
J 2
(-7723 3375);
DISPLAY 0.872340 (-7723 3375);
PAINT GREEN (-7723 3375);
DISPLAY INVISIBLE (-7723 3375);
FORCEADD TAP..1
R 2
(-7725 3325);
FORCEPROP 3 LASTPIN (-7675 3325) SIG_NAME M_L_CPU0_SA_CB<0>
J 0
(-7665 3335);
DISPLAY 0.659574 (-7665 3335);
PAINT MONO (-7665 3335);
DISPLAY INVISIBLE (-7665 3335);
FORCEPROP 1 LASTPIN (-7675 3325) BN 0
J 2
(-7663 3333);
DISPLAY 0.489362 (-7663 3333);
PAINT GREEN (-7663 3333);
FORCEPROP 2 LAST CDS_LIB mstr_standard
J 0
(-7725 3325);
DISPLAY 0.723404 (-7725 3325);
PAINT MONO (-7725 3325);
DISPLAY INVISIBLE (-7725 3325);
FORCEPROP 1 LAST BODY_TYPE PLUMBING
J 2
(-7725 3375);
DISPLAY 0.872340 (-7725 3375);
PAINT GREEN (-7725 3375);
DISPLAY INVISIBLE (-7725 3375);
FORCEPROP 1 LAST HDL_TAP TRUE
J 2
(-8050 3200);
DISPLAY 0.872340 (-8050 3200);
DISPLAY INVISIBLE (-8050 3200);
FORCEPROP 1 LAST PATH I31
J 2
(-7723 3325);
DISPLAY 0.872340 (-7723 3325);
PAINT GREEN (-7723 3325);
DISPLAY INVISIBLE (-7723 3325);
FORCEADD TAP..1
R 2
(-7725 3175);
FORCEPROP 3 LASTPIN (-7675 3175) SIG_NAME M_L_CPU0_SB_CB<6>
J 0
(-7665 3185);
DISPLAY 0.659574 (-7665 3185);
PAINT MONO (-7665 3185);
DISPLAY INVISIBLE (-7665 3185);
FORCEPROP 1 LASTPIN (-7675 3175) BN 6
J 2
(-7663 3183);
DISPLAY 0.489362 (-7663 3183);
PAINT GREEN (-7663 3183);
FORCEPROP 2 LAST CDS_LIB mstr_standard
J 0
(-7725 3175);
DISPLAY 0.723404 (-7725 3175);
PAINT MONO (-7725 3175);
DISPLAY INVISIBLE (-7725 3175);
FORCEPROP 1 LAST BODY_TYPE PLUMBING
J 2
(-7725 3225);
DISPLAY 0.872340 (-7725 3225);
PAINT GREEN (-7725 3225);
DISPLAY INVISIBLE (-7725 3225);
FORCEPROP 1 LAST HDL_TAP TRUE
J 2
(-8050 3050);
DISPLAY 0.872340 (-8050 3050);
DISPLAY INVISIBLE (-8050 3050);
FORCEPROP 1 LAST PATH I32
J 2
(-7723 3175);
DISPLAY 0.872340 (-7723 3175);
PAINT GREEN (-7723 3175);
DISPLAY INVISIBLE (-7723 3175);
FORCEADD TAP..1
(-6025 1875);
FORCEPROP 3 LASTPIN (-6075 1875) SIG_NAME M_L_CPU0_SB_DQ<0>
J 0
(-6065 1885);
DISPLAY 0.659574 (-6065 1885);
PAINT MONO (-6065 1885);
DISPLAY INVISIBLE (-6065 1885);
FORCEPROP 1 LASTPIN (-6075 1875) BN 0
J 0
(-6087 1883);
DISPLAY 0.489362 (-6087 1883);
PAINT GREEN (-6087 1883);
FORCEPROP 2 LAST CDS_LIB mstr_standard
J 0
(-6025 1875);
DISPLAY 0.723404 (-6025 1875);
PAINT MONO (-6025 1875);
DISPLAY INVISIBLE (-6025 1875);
FORCEPROP 1 LAST BODY_TYPE PLUMBING
J 0
(-6025 1925);
DISPLAY 0.872340 (-6025 1925);
PAINT GREEN (-6025 1925);
DISPLAY INVISIBLE (-6025 1925);
FORCEPROP 1 LAST HDL_TAP TRUE
J 0
(-5700 1750);
DISPLAY 0.872340 (-5700 1750);
DISPLAY INVISIBLE (-5700 1750);
FORCEPROP 1 LAST PATH I33
J 0
(-6027 1875);
DISPLAY 0.872340 (-6027 1875);
PAINT GREEN (-6027 1875);
DISPLAY INVISIBLE (-6027 1875);
FORCEADD TAP..1
(-6025 1925);
FORCEPROP 3 LASTPIN (-6075 1925) SIG_NAME M_L_CPU0_SB_DQ<1>
J 0
(-6065 1935);
DISPLAY 0.659574 (-6065 1935);
PAINT MONO (-6065 1935);
DISPLAY INVISIBLE (-6065 1935);
FORCEPROP 1 LASTPIN (-6075 1925) BN 1
J 0
(-6087 1933);
DISPLAY 0.489362 (-6087 1933);
PAINT GREEN (-6087 1933);
FORCEPROP 2 LAST CDS_LIB mstr_standard
J 0
(-6025 1925);
DISPLAY 0.723404 (-6025 1925);
PAINT MONO (-6025 1925);
DISPLAY INVISIBLE (-6025 1925);
FORCEPROP 1 LAST BODY_TYPE PLUMBING
J 0
(-6025 1975);
DISPLAY 0.872340 (-6025 1975);
PAINT GREEN (-6025 1975);
DISPLAY INVISIBLE (-6025 1975);
FORCEPROP 1 LAST HDL_TAP TRUE
J 0
(-5700 1800);
DISPLAY 0.872340 (-5700 1800);
DISPLAY INVISIBLE (-5700 1800);
FORCEPROP 1 LAST PATH I34
J 0
(-6027 1925);
DISPLAY 0.872340 (-6027 1925);
PAINT GREEN (-6027 1925);
DISPLAY INVISIBLE (-6027 1925);
FORCEADD TAP..1
(-6025 1975);
FORCEPROP 3 LASTPIN (-6075 1975) SIG_NAME M_L_CPU0_SB_DQ<2>
J 0
(-6065 1985);
DISPLAY 0.659574 (-6065 1985);
PAINT MONO (-6065 1985);
DISPLAY INVISIBLE (-6065 1985);
FORCEPROP 1 LASTPIN (-6075 1975) BN 2
J 0
(-6087 1983);
DISPLAY 0.489362 (-6087 1983);
PAINT GREEN (-6087 1983);
FORCEPROP 2 LAST CDS_LIB mstr_standard
J 0
(-6025 1975);
DISPLAY 0.723404 (-6025 1975);
PAINT MONO (-6025 1975);
DISPLAY INVISIBLE (-6025 1975);
FORCEPROP 1 LAST BODY_TYPE PLUMBING
J 0
(-6025 2025);
DISPLAY 0.872340 (-6025 2025);
PAINT GREEN (-6025 2025);
DISPLAY INVISIBLE (-6025 2025);
FORCEPROP 1 LAST HDL_TAP TRUE
J 0
(-5700 1850);
DISPLAY 0.872340 (-5700 1850);
DISPLAY INVISIBLE (-5700 1850);
FORCEPROP 1 LAST PATH I35
J 0
(-6027 1975);
DISPLAY 0.872340 (-6027 1975);
PAINT GREEN (-6027 1975);
DISPLAY INVISIBLE (-6027 1975);
FORCEADD TAP..1
(-6025 2025);
FORCEPROP 3 LASTPIN (-6075 2025) SIG_NAME M_L_CPU0_SB_DQ<3>
J 0
(-6065 2035);
DISPLAY 0.659574 (-6065 2035);
PAINT MONO (-6065 2035);
DISPLAY INVISIBLE (-6065 2035);
FORCEPROP 1 LASTPIN (-6075 2025) BN 3
J 0
(-6087 2033);
DISPLAY 0.489362 (-6087 2033);
PAINT GREEN (-6087 2033);
FORCEPROP 2 LAST CDS_LIB mstr_standard
J 0
(-6025 2025);
DISPLAY 0.723404 (-6025 2025);
PAINT MONO (-6025 2025);
DISPLAY INVISIBLE (-6025 2025);
FORCEPROP 1 LAST BODY_TYPE PLUMBING
J 0
(-6025 2075);
DISPLAY 0.872340 (-6025 2075);
PAINT GREEN (-6025 2075);
DISPLAY INVISIBLE (-6025 2075);
FORCEPROP 1 LAST HDL_TAP TRUE
J 0
(-5700 1900);
DISPLAY 0.872340 (-5700 1900);
DISPLAY INVISIBLE (-5700 1900);
FORCEPROP 1 LAST PATH I36
J 0
(-6027 2025);
DISPLAY 0.872340 (-6027 2025);
PAINT GREEN (-6027 2025);
DISPLAY INVISIBLE (-6027 2025);
FORCEADD TAP..1
(-6025 2075);
FORCEPROP 3 LASTPIN (-6075 2075) SIG_NAME M_L_CPU0_SB_DQ<4>
J 0
(-6065 2085);
DISPLAY 0.659574 (-6065 2085);
PAINT MONO (-6065 2085);
DISPLAY INVISIBLE (-6065 2085);
FORCEPROP 1 LASTPIN (-6075 2075) BN 4
J 0
(-6087 2083);
DISPLAY 0.489362 (-6087 2083);
PAINT GREEN (-6087 2083);
FORCEPROP 2 LAST CDS_LIB mstr_standard
J 0
(-6025 2075);
DISPLAY 0.723404 (-6025 2075);
PAINT MONO (-6025 2075);
DISPLAY INVISIBLE (-6025 2075);
FORCEPROP 1 LAST BODY_TYPE PLUMBING
J 0
(-6025 2125);
DISPLAY 0.872340 (-6025 2125);
PAINT GREEN (-6025 2125);
DISPLAY INVISIBLE (-6025 2125);
FORCEPROP 1 LAST HDL_TAP TRUE
J 0
(-5700 1950);
DISPLAY 0.872340 (-5700 1950);
DISPLAY INVISIBLE (-5700 1950);
FORCEPROP 1 LAST PATH I37
J 0
(-6027 2075);
DISPLAY 0.872340 (-6027 2075);
PAINT GREEN (-6027 2075);
DISPLAY INVISIBLE (-6027 2075);
FORCEADD TAP..1
(-6025 2125);
FORCEPROP 3 LASTPIN (-6075 2125) SIG_NAME M_L_CPU0_SB_DQ<5>
J 0
(-6065 2135);
DISPLAY 0.659574 (-6065 2135);
PAINT MONO (-6065 2135);
DISPLAY INVISIBLE (-6065 2135);
FORCEPROP 1 LASTPIN (-6075 2125) BN 5
J 0
(-6087 2133);
DISPLAY 0.489362 (-6087 2133);
PAINT GREEN (-6087 2133);
FORCEPROP 2 LAST CDS_LIB mstr_standard
J 0
(-6025 2125);
DISPLAY 0.723404 (-6025 2125);
PAINT MONO (-6025 2125);
DISPLAY INVISIBLE (-6025 2125);
FORCEPROP 1 LAST BODY_TYPE PLUMBING
J 0
(-6025 2175);
DISPLAY 0.872340 (-6025 2175);
PAINT GREEN (-6025 2175);
DISPLAY INVISIBLE (-6025 2175);
FORCEPROP 1 LAST HDL_TAP TRUE
J 0
(-5700 2000);
DISPLAY 0.872340 (-5700 2000);
DISPLAY INVISIBLE (-5700 2000);
FORCEPROP 1 LAST PATH I38
J 0
(-6027 2125);
DISPLAY 0.872340 (-6027 2125);
PAINT GREEN (-6027 2125);
DISPLAY INVISIBLE (-6027 2125);
FORCEADD TAP..1
(-6025 2175);
FORCEPROP 3 LASTPIN (-6075 2175) SIG_NAME M_L_CPU0_SB_DQ<6>
J 0
(-6065 2185);
DISPLAY 0.659574 (-6065 2185);
PAINT MONO (-6065 2185);
DISPLAY INVISIBLE (-6065 2185);
FORCEPROP 1 LASTPIN (-6075 2175) BN 6
J 0
(-6087 2183);
DISPLAY 0.489362 (-6087 2183);
PAINT GREEN (-6087 2183);
FORCEPROP 2 LAST CDS_LIB mstr_standard
J 0
(-6025 2175);
DISPLAY 0.723404 (-6025 2175);
PAINT MONO (-6025 2175);
DISPLAY INVISIBLE (-6025 2175);
FORCEPROP 1 LAST BODY_TYPE PLUMBING
J 0
(-6025 2225);
DISPLAY 0.872340 (-6025 2225);
PAINT GREEN (-6025 2225);
DISPLAY INVISIBLE (-6025 2225);
FORCEPROP 1 LAST HDL_TAP TRUE
J 0
(-5700 2050);
DISPLAY 0.872340 (-5700 2050);
DISPLAY INVISIBLE (-5700 2050);
FORCEPROP 1 LAST PATH I39
J 0
(-6027 2175);
DISPLAY 0.872340 (-6027 2175);
PAINT GREEN (-6027 2175);
DISPLAY INVISIBLE (-6027 2175);
FORCEADD TAP..1
(-6025 2225);
FORCEPROP 3 LASTPIN (-6075 2225) SIG_NAME M_L_CPU0_SB_DQ<7>
J 0
(-6065 2235);
DISPLAY 0.659574 (-6065 2235);
PAINT MONO (-6065 2235);
DISPLAY INVISIBLE (-6065 2235);
FORCEPROP 1 LASTPIN (-6075 2225) BN 7
J 0
(-6087 2233);
DISPLAY 0.489362 (-6087 2233);
PAINT GREEN (-6087 2233);
FORCEPROP 2 LAST CDS_LIB mstr_standard
J 0
(-6025 2225);
DISPLAY 0.723404 (-6025 2225);
PAINT MONO (-6025 2225);
DISPLAY INVISIBLE (-6025 2225);
FORCEPROP 1 LAST BODY_TYPE PLUMBING
J 0
(-6025 2275);
DISPLAY 0.872340 (-6025 2275);
PAINT GREEN (-6025 2275);
DISPLAY INVISIBLE (-6025 2275);
FORCEPROP 1 LAST HDL_TAP TRUE
J 0
(-5700 2100);
DISPLAY 0.872340 (-5700 2100);
DISPLAY INVISIBLE (-5700 2100);
FORCEPROP 1 LAST PATH I40
J 0
(-6027 2225);
DISPLAY 0.872340 (-6027 2225);
PAINT GREEN (-6027 2225);
DISPLAY INVISIBLE (-6027 2225);
FORCEADD TAP..1
(-6025 2275);
FORCEPROP 3 LASTPIN (-6075 2275) SIG_NAME M_L_CPU0_SB_DQ<8>
J 0
(-6065 2285);
DISPLAY 0.659574 (-6065 2285);
PAINT MONO (-6065 2285);
DISPLAY INVISIBLE (-6065 2285);
FORCEPROP 1 LASTPIN (-6075 2275) BN 8
J 0
(-6087 2283);
DISPLAY 0.489362 (-6087 2283);
PAINT GREEN (-6087 2283);
FORCEPROP 2 LAST CDS_LIB mstr_standard
J 0
(-6025 2275);
DISPLAY 0.723404 (-6025 2275);
PAINT MONO (-6025 2275);
DISPLAY INVISIBLE (-6025 2275);
FORCEPROP 1 LAST BODY_TYPE PLUMBING
J 0
(-6025 2325);
DISPLAY 0.872340 (-6025 2325);
PAINT GREEN (-6025 2325);
DISPLAY INVISIBLE (-6025 2325);
FORCEPROP 1 LAST HDL_TAP TRUE
J 0
(-5700 2150);
DISPLAY 0.872340 (-5700 2150);
DISPLAY INVISIBLE (-5700 2150);
FORCEPROP 1 LAST PATH I41
J 0
(-6027 2275);
DISPLAY 0.872340 (-6027 2275);
PAINT GREEN (-6027 2275);
DISPLAY INVISIBLE (-6027 2275);
FORCEADD TAP..1
(-6025 2375);
FORCEPROP 3 LASTPIN (-6075 2375) SIG_NAME M_L_CPU0_SB_DQ<10>
J 0
(-6065 2385);
DISPLAY 0.659574 (-6065 2385);
PAINT MONO (-6065 2385);
DISPLAY INVISIBLE (-6065 2385);
FORCEPROP 1 LASTPIN (-6075 2375) BN 10
J 0
(-6087 2383);
DISPLAY 0.489362 (-6087 2383);
PAINT GREEN (-6087 2383);
FORCEPROP 2 LAST CDS_LIB mstr_standard
J 0
(-6025 2375);
DISPLAY 0.723404 (-6025 2375);
PAINT MONO (-6025 2375);
DISPLAY INVISIBLE (-6025 2375);
FORCEPROP 1 LAST BODY_TYPE PLUMBING
J 0
(-6025 2425);
DISPLAY 0.872340 (-6025 2425);
PAINT GREEN (-6025 2425);
DISPLAY INVISIBLE (-6025 2425);
FORCEPROP 1 LAST HDL_TAP TRUE
J 0
(-5700 2250);
DISPLAY 0.872340 (-5700 2250);
DISPLAY INVISIBLE (-5700 2250);
FORCEPROP 1 LAST PATH I42
J 0
(-6027 2375);
DISPLAY 0.872340 (-6027 2375);
PAINT GREEN (-6027 2375);
DISPLAY INVISIBLE (-6027 2375);
FORCEADD TAP..1
(-6025 2325);
FORCEPROP 3 LASTPIN (-6075 2325) SIG_NAME M_L_CPU0_SB_DQ<9>
J 0
(-6065 2335);
DISPLAY 0.659574 (-6065 2335);
PAINT MONO (-6065 2335);
DISPLAY INVISIBLE (-6065 2335);
FORCEPROP 1 LASTPIN (-6075 2325) BN 9
J 0
(-6087 2333);
DISPLAY 0.489362 (-6087 2333);
PAINT GREEN (-6087 2333);
FORCEPROP 2 LAST CDS_LIB mstr_standard
J 0
(-6025 2325);
DISPLAY 0.723404 (-6025 2325);
PAINT MONO (-6025 2325);
DISPLAY INVISIBLE (-6025 2325);
FORCEPROP 1 LAST BODY_TYPE PLUMBING
J 0
(-6025 2375);
DISPLAY 0.872340 (-6025 2375);
PAINT GREEN (-6025 2375);
DISPLAY INVISIBLE (-6025 2375);
FORCEPROP 1 LAST HDL_TAP TRUE
J 0
(-5700 2200);
DISPLAY 0.872340 (-5700 2200);
DISPLAY INVISIBLE (-5700 2200);
FORCEPROP 1 LAST PATH I43
J 0
(-6027 2325);
DISPLAY 0.872340 (-6027 2325);
PAINT GREEN (-6027 2325);
DISPLAY INVISIBLE (-6027 2325);
FORCEADD TAP..1
(-6025 2425);
FORCEPROP 3 LASTPIN (-6075 2425) SIG_NAME M_L_CPU0_SB_DQ<11>
J 0
(-6065 2435);
DISPLAY 0.659574 (-6065 2435);
PAINT MONO (-6065 2435);
DISPLAY INVISIBLE (-6065 2435);
FORCEPROP 1 LASTPIN (-6075 2425) BN 11
J 0
(-6087 2433);
DISPLAY 0.489362 (-6087 2433);
PAINT GREEN (-6087 2433);
FORCEPROP 2 LAST CDS_LIB mstr_standard
J 0
(-6025 2425);
DISPLAY 0.723404 (-6025 2425);
PAINT MONO (-6025 2425);
DISPLAY INVISIBLE (-6025 2425);
FORCEPROP 1 LAST BODY_TYPE PLUMBING
J 0
(-6025 2475);
DISPLAY 0.872340 (-6025 2475);
PAINT GREEN (-6025 2475);
DISPLAY INVISIBLE (-6025 2475);
FORCEPROP 1 LAST HDL_TAP TRUE
J 0
(-5700 2300);
DISPLAY 0.872340 (-5700 2300);
DISPLAY INVISIBLE (-5700 2300);
FORCEPROP 1 LAST PATH I44
J 0
(-6027 2425);
DISPLAY 0.872340 (-6027 2425);
PAINT GREEN (-6027 2425);
DISPLAY INVISIBLE (-6027 2425);
FORCEADD TAP..1
(-6025 2475);
FORCEPROP 3 LASTPIN (-6075 2475) SIG_NAME M_L_CPU0_SB_DQ<12>
J 0
(-6065 2485);
DISPLAY 0.659574 (-6065 2485);
PAINT MONO (-6065 2485);
DISPLAY INVISIBLE (-6065 2485);
FORCEPROP 1 LASTPIN (-6075 2475) BN 12
J 0
(-6087 2483);
DISPLAY 0.489362 (-6087 2483);
PAINT GREEN (-6087 2483);
FORCEPROP 2 LAST CDS_LIB mstr_standard
J 0
(-6025 2475);
DISPLAY 0.723404 (-6025 2475);
PAINT MONO (-6025 2475);
DISPLAY INVISIBLE (-6025 2475);
FORCEPROP 1 LAST BODY_TYPE PLUMBING
J 0
(-6025 2525);
DISPLAY 0.872340 (-6025 2525);
PAINT GREEN (-6025 2525);
DISPLAY INVISIBLE (-6025 2525);
FORCEPROP 1 LAST HDL_TAP TRUE
J 0
(-5700 2350);
DISPLAY 0.872340 (-5700 2350);
DISPLAY INVISIBLE (-5700 2350);
FORCEPROP 1 LAST PATH I45
J 0
(-6027 2475);
DISPLAY 0.872340 (-6027 2475);
PAINT GREEN (-6027 2475);
DISPLAY INVISIBLE (-6027 2475);
FORCEADD TAP..1
(-6025 2525);
FORCEPROP 3 LASTPIN (-6075 2525) SIG_NAME M_L_CPU0_SB_DQ<13>
J 0
(-6065 2535);
DISPLAY 0.659574 (-6065 2535);
PAINT MONO (-6065 2535);
DISPLAY INVISIBLE (-6065 2535);
FORCEPROP 1 LASTPIN (-6075 2525) BN 13
J 0
(-6087 2533);
DISPLAY 0.489362 (-6087 2533);
PAINT GREEN (-6087 2533);
FORCEPROP 2 LAST CDS_LIB mstr_standard
J 0
(-6025 2525);
DISPLAY 0.723404 (-6025 2525);
PAINT MONO (-6025 2525);
DISPLAY INVISIBLE (-6025 2525);
FORCEPROP 1 LAST BODY_TYPE PLUMBING
J 0
(-6025 2575);
DISPLAY 0.872340 (-6025 2575);
PAINT GREEN (-6025 2575);
DISPLAY INVISIBLE (-6025 2575);
FORCEPROP 1 LAST HDL_TAP TRUE
J 0
(-5700 2400);
DISPLAY 0.872340 (-5700 2400);
DISPLAY INVISIBLE (-5700 2400);
FORCEPROP 1 LAST PATH I46
J 0
(-6027 2525);
DISPLAY 0.872340 (-6027 2525);
PAINT GREEN (-6027 2525);
DISPLAY INVISIBLE (-6027 2525);
FORCEADD TAP..1
(-6025 2575);
FORCEPROP 3 LASTPIN (-6075 2575) SIG_NAME M_L_CPU0_SB_DQ<14>
J 0
(-6065 2585);
DISPLAY 0.659574 (-6065 2585);
PAINT MONO (-6065 2585);
DISPLAY INVISIBLE (-6065 2585);
FORCEPROP 1 LASTPIN (-6075 2575) BN 14
J 0
(-6087 2583);
DISPLAY 0.489362 (-6087 2583);
PAINT GREEN (-6087 2583);
FORCEPROP 2 LAST CDS_LIB mstr_standard
J 0
(-6025 2575);
DISPLAY 0.723404 (-6025 2575);
PAINT MONO (-6025 2575);
DISPLAY INVISIBLE (-6025 2575);
FORCEPROP 1 LAST BODY_TYPE PLUMBING
J 0
(-6025 2625);
DISPLAY 0.872340 (-6025 2625);
PAINT GREEN (-6025 2625);
DISPLAY INVISIBLE (-6025 2625);
FORCEPROP 1 LAST HDL_TAP TRUE
J 0
(-5700 2450);
DISPLAY 0.872340 (-5700 2450);
DISPLAY INVISIBLE (-5700 2450);
FORCEPROP 1 LAST PATH I47
J 0
(-6027 2575);
DISPLAY 0.872340 (-6027 2575);
PAINT GREEN (-6027 2575);
DISPLAY INVISIBLE (-6027 2575);
FORCEADD TAP..1
(-6025 2625);
FORCEPROP 3 LASTPIN (-6075 2625) SIG_NAME M_L_CPU0_SB_DQ<15>
J 0
(-6065 2635);
DISPLAY 0.659574 (-6065 2635);
PAINT MONO (-6065 2635);
DISPLAY INVISIBLE (-6065 2635);
FORCEPROP 1 LASTPIN (-6075 2625) BN 15
J 0
(-6087 2633);
DISPLAY 0.489362 (-6087 2633);
PAINT GREEN (-6087 2633);
FORCEPROP 2 LAST CDS_LIB mstr_standard
J 0
(-6025 2625);
DISPLAY 0.723404 (-6025 2625);
PAINT MONO (-6025 2625);
DISPLAY INVISIBLE (-6025 2625);
FORCEPROP 1 LAST BODY_TYPE PLUMBING
J 0
(-6025 2675);
DISPLAY 0.872340 (-6025 2675);
PAINT GREEN (-6025 2675);
DISPLAY INVISIBLE (-6025 2675);
FORCEPROP 1 LAST HDL_TAP TRUE
J 0
(-5700 2500);
DISPLAY 0.872340 (-5700 2500);
DISPLAY INVISIBLE (-5700 2500);
FORCEPROP 1 LAST PATH I48
J 0
(-6027 2625);
DISPLAY 0.872340 (-6027 2625);
PAINT GREEN (-6027 2625);
DISPLAY INVISIBLE (-6027 2625);
FORCEADD TAP..1
(-6025 2675);
FORCEPROP 3 LASTPIN (-6075 2675) SIG_NAME M_L_CPU0_SB_DQ<16>
J 0
(-6065 2685);
DISPLAY 0.659574 (-6065 2685);
PAINT MONO (-6065 2685);
DISPLAY INVISIBLE (-6065 2685);
FORCEPROP 1 LASTPIN (-6075 2675) BN 16
J 0
(-6087 2683);
DISPLAY 0.489362 (-6087 2683);
PAINT GREEN (-6087 2683);
FORCEPROP 2 LAST CDS_LIB mstr_standard
J 0
(-6025 2675);
DISPLAY 0.723404 (-6025 2675);
PAINT MONO (-6025 2675);
DISPLAY INVISIBLE (-6025 2675);
FORCEPROP 1 LAST BODY_TYPE PLUMBING
J 0
(-6025 2725);
DISPLAY 0.872340 (-6025 2725);
PAINT GREEN (-6025 2725);
DISPLAY INVISIBLE (-6025 2725);
FORCEPROP 1 LAST HDL_TAP TRUE
J 0
(-5700 2550);
DISPLAY 0.872340 (-5700 2550);
DISPLAY INVISIBLE (-5700 2550);
FORCEPROP 1 LAST PATH I49
J 0
(-6027 2675);
DISPLAY 0.872340 (-6027 2675);
PAINT GREEN (-6027 2675);
DISPLAY INVISIBLE (-6027 2675);
FORCEADD TAP..1
(-6025 2725);
FORCEPROP 3 LASTPIN (-6075 2725) SIG_NAME M_L_CPU0_SB_DQ<17>
J 0
(-6065 2735);
DISPLAY 0.659574 (-6065 2735);
PAINT MONO (-6065 2735);
DISPLAY INVISIBLE (-6065 2735);
FORCEPROP 1 LASTPIN (-6075 2725) BN 17
J 0
(-6087 2733);
DISPLAY 0.489362 (-6087 2733);
PAINT GREEN (-6087 2733);
FORCEPROP 2 LAST CDS_LIB mstr_standard
J 0
(-6025 2725);
DISPLAY 0.723404 (-6025 2725);
PAINT MONO (-6025 2725);
DISPLAY INVISIBLE (-6025 2725);
FORCEPROP 1 LAST BODY_TYPE PLUMBING
J 0
(-6025 2775);
DISPLAY 0.872340 (-6025 2775);
PAINT GREEN (-6025 2775);
DISPLAY INVISIBLE (-6025 2775);
FORCEPROP 1 LAST HDL_TAP TRUE
J 0
(-5700 2600);
DISPLAY 0.872340 (-5700 2600);
DISPLAY INVISIBLE (-5700 2600);
FORCEPROP 1 LAST PATH I50
J 0
(-6027 2725);
DISPLAY 0.872340 (-6027 2725);
PAINT GREEN (-6027 2725);
DISPLAY INVISIBLE (-6027 2725);
FORCEADD TAP..1
(-6025 2775);
FORCEPROP 3 LASTPIN (-6075 2775) SIG_NAME M_L_CPU0_SB_DQ<18>
J 0
(-6065 2785);
DISPLAY 0.659574 (-6065 2785);
PAINT MONO (-6065 2785);
DISPLAY INVISIBLE (-6065 2785);
FORCEPROP 1 LASTPIN (-6075 2775) BN 18
J 0
(-6087 2783);
DISPLAY 0.489362 (-6087 2783);
PAINT GREEN (-6087 2783);
FORCEPROP 2 LAST CDS_LIB mstr_standard
J 0
(-6025 2775);
DISPLAY 0.723404 (-6025 2775);
PAINT MONO (-6025 2775);
DISPLAY INVISIBLE (-6025 2775);
FORCEPROP 1 LAST BODY_TYPE PLUMBING
J 0
(-6025 2825);
DISPLAY 0.872340 (-6025 2825);
PAINT GREEN (-6025 2825);
DISPLAY INVISIBLE (-6025 2825);
FORCEPROP 1 LAST HDL_TAP TRUE
J 0
(-5700 2650);
DISPLAY 0.872340 (-5700 2650);
DISPLAY INVISIBLE (-5700 2650);
FORCEPROP 1 LAST PATH I51
J 0
(-6027 2775);
DISPLAY 0.872340 (-6027 2775);
PAINT GREEN (-6027 2775);
DISPLAY INVISIBLE (-6027 2775);
FORCEADD TAP..1
(-6025 2825);
FORCEPROP 3 LASTPIN (-6075 2825) SIG_NAME M_L_CPU0_SB_DQ<19>
J 0
(-6065 2835);
DISPLAY 0.659574 (-6065 2835);
PAINT MONO (-6065 2835);
DISPLAY INVISIBLE (-6065 2835);
FORCEPROP 1 LASTPIN (-6075 2825) BN 19
J 0
(-6087 2833);
DISPLAY 0.489362 (-6087 2833);
PAINT GREEN (-6087 2833);
FORCEPROP 2 LAST CDS_LIB mstr_standard
J 0
(-6025 2825);
DISPLAY 0.723404 (-6025 2825);
PAINT MONO (-6025 2825);
DISPLAY INVISIBLE (-6025 2825);
FORCEPROP 1 LAST BODY_TYPE PLUMBING
J 0
(-6025 2875);
DISPLAY 0.872340 (-6025 2875);
PAINT GREEN (-6025 2875);
DISPLAY INVISIBLE (-6025 2875);
FORCEPROP 1 LAST HDL_TAP TRUE
J 0
(-5700 2700);
DISPLAY 0.872340 (-5700 2700);
DISPLAY INVISIBLE (-5700 2700);
FORCEPROP 1 LAST PATH I52
J 0
(-6027 2825);
DISPLAY 0.872340 (-6027 2825);
PAINT GREEN (-6027 2825);
DISPLAY INVISIBLE (-6027 2825);
FORCEADD TAP..1
(-6025 2875);
FORCEPROP 3 LASTPIN (-6075 2875) SIG_NAME M_L_CPU0_SB_DQ<20>
J 0
(-6065 2885);
DISPLAY 0.659574 (-6065 2885);
PAINT MONO (-6065 2885);
DISPLAY INVISIBLE (-6065 2885);
FORCEPROP 1 LASTPIN (-6075 2875) BN 20
J 0
(-6087 2883);
DISPLAY 0.489362 (-6087 2883);
PAINT GREEN (-6087 2883);
FORCEPROP 2 LAST CDS_LIB mstr_standard
J 0
(-6025 2875);
DISPLAY 0.723404 (-6025 2875);
PAINT MONO (-6025 2875);
DISPLAY INVISIBLE (-6025 2875);
FORCEPROP 1 LAST BODY_TYPE PLUMBING
J 0
(-6025 2925);
DISPLAY 0.872340 (-6025 2925);
PAINT GREEN (-6025 2925);
DISPLAY INVISIBLE (-6025 2925);
FORCEPROP 1 LAST HDL_TAP TRUE
J 0
(-5700 2750);
DISPLAY 0.872340 (-5700 2750);
DISPLAY INVISIBLE (-5700 2750);
FORCEPROP 1 LAST PATH I53
J 0
(-6027 2875);
DISPLAY 0.872340 (-6027 2875);
PAINT GREEN (-6027 2875);
DISPLAY INVISIBLE (-6027 2875);
FORCEADD TAP..1
(-6025 2925);
FORCEPROP 3 LASTPIN (-6075 2925) SIG_NAME M_L_CPU0_SB_DQ<21>
J 0
(-6065 2935);
DISPLAY 0.659574 (-6065 2935);
PAINT MONO (-6065 2935);
DISPLAY INVISIBLE (-6065 2935);
FORCEPROP 1 LASTPIN (-6075 2925) BN 21
J 0
(-6087 2933);
DISPLAY 0.489362 (-6087 2933);
PAINT GREEN (-6087 2933);
FORCEPROP 2 LAST CDS_LIB mstr_standard
J 0
(-6025 2925);
DISPLAY 0.723404 (-6025 2925);
PAINT MONO (-6025 2925);
DISPLAY INVISIBLE (-6025 2925);
FORCEPROP 1 LAST BODY_TYPE PLUMBING
J 0
(-6025 2975);
DISPLAY 0.872340 (-6025 2975);
PAINT GREEN (-6025 2975);
DISPLAY INVISIBLE (-6025 2975);
FORCEPROP 1 LAST HDL_TAP TRUE
J 0
(-5700 2800);
DISPLAY 0.872340 (-5700 2800);
DISPLAY INVISIBLE (-5700 2800);
FORCEPROP 1 LAST PATH I54
J 0
(-6027 2925);
DISPLAY 0.872340 (-6027 2925);
PAINT GREEN (-6027 2925);
DISPLAY INVISIBLE (-6027 2925);
FORCEADD TAP..1
(-6025 2975);
FORCEPROP 3 LASTPIN (-6075 2975) SIG_NAME M_L_CPU0_SB_DQ<22>
J 0
(-6065 2985);
DISPLAY 0.659574 (-6065 2985);
PAINT MONO (-6065 2985);
DISPLAY INVISIBLE (-6065 2985);
FORCEPROP 1 LASTPIN (-6075 2975) BN 22
J 0
(-6087 2983);
DISPLAY 0.489362 (-6087 2983);
PAINT GREEN (-6087 2983);
FORCEPROP 2 LAST CDS_LIB mstr_standard
J 0
(-6025 2975);
DISPLAY 0.723404 (-6025 2975);
PAINT MONO (-6025 2975);
DISPLAY INVISIBLE (-6025 2975);
FORCEPROP 1 LAST BODY_TYPE PLUMBING
J 0
(-6025 3025);
DISPLAY 0.872340 (-6025 3025);
PAINT GREEN (-6025 3025);
DISPLAY INVISIBLE (-6025 3025);
FORCEPROP 1 LAST HDL_TAP TRUE
J 0
(-5700 2850);
DISPLAY 0.872340 (-5700 2850);
DISPLAY INVISIBLE (-5700 2850);
FORCEPROP 1 LAST PATH I55
J 0
(-6027 2975);
DISPLAY 0.872340 (-6027 2975);
PAINT GREEN (-6027 2975);
DISPLAY INVISIBLE (-6027 2975);
FORCEADD TAP..1
(-6025 3025);
FORCEPROP 3 LASTPIN (-6075 3025) SIG_NAME M_L_CPU0_SB_DQ<23>
J 0
(-6065 3035);
DISPLAY 0.659574 (-6065 3035);
PAINT MONO (-6065 3035);
DISPLAY INVISIBLE (-6065 3035);
FORCEPROP 1 LASTPIN (-6075 3025) BN 23
J 0
(-6087 3033);
DISPLAY 0.489362 (-6087 3033);
PAINT GREEN (-6087 3033);
FORCEPROP 2 LAST CDS_LIB mstr_standard
J 0
(-6025 3025);
DISPLAY 0.723404 (-6025 3025);
PAINT MONO (-6025 3025);
DISPLAY INVISIBLE (-6025 3025);
FORCEPROP 1 LAST BODY_TYPE PLUMBING
J 0
(-6025 3075);
DISPLAY 0.872340 (-6025 3075);
PAINT GREEN (-6025 3075);
DISPLAY INVISIBLE (-6025 3075);
FORCEPROP 1 LAST HDL_TAP TRUE
J 0
(-5700 2900);
DISPLAY 0.872340 (-5700 2900);
DISPLAY INVISIBLE (-5700 2900);
FORCEPROP 1 LAST PATH I56
J 0
(-6027 3025);
DISPLAY 0.872340 (-6027 3025);
PAINT GREEN (-6027 3025);
DISPLAY INVISIBLE (-6027 3025);
FORCEADD TAP..1
(-6025 3075);
FORCEPROP 3 LASTPIN (-6075 3075) SIG_NAME M_L_CPU0_SB_DQ<24>
J 0
(-6065 3085);
DISPLAY 0.659574 (-6065 3085);
PAINT MONO (-6065 3085);
DISPLAY INVISIBLE (-6065 3085);
FORCEPROP 1 LASTPIN (-6075 3075) BN 24
J 0
(-6087 3083);
DISPLAY 0.489362 (-6087 3083);
PAINT GREEN (-6087 3083);
FORCEPROP 2 LAST CDS_LIB mstr_standard
J 0
(-6025 3075);
DISPLAY 0.723404 (-6025 3075);
PAINT MONO (-6025 3075);
DISPLAY INVISIBLE (-6025 3075);
FORCEPROP 1 LAST BODY_TYPE PLUMBING
J 0
(-6025 3125);
DISPLAY 0.872340 (-6025 3125);
PAINT GREEN (-6025 3125);
DISPLAY INVISIBLE (-6025 3125);
FORCEPROP 1 LAST HDL_TAP TRUE
J 0
(-5700 2950);
DISPLAY 0.872340 (-5700 2950);
DISPLAY INVISIBLE (-5700 2950);
FORCEPROP 1 LAST PATH I57
J 0
(-6027 3075);
DISPLAY 0.872340 (-6027 3075);
PAINT GREEN (-6027 3075);
DISPLAY INVISIBLE (-6027 3075);
FORCEADD TAP..1
(-6025 3125);
FORCEPROP 3 LASTPIN (-6075 3125) SIG_NAME M_L_CPU0_SB_DQ<25>
J 0
(-6065 3135);
DISPLAY 0.659574 (-6065 3135);
PAINT MONO (-6065 3135);
DISPLAY INVISIBLE (-6065 3135);
FORCEPROP 1 LASTPIN (-6075 3125) BN 25
J 0
(-6087 3133);
DISPLAY 0.489362 (-6087 3133);
PAINT GREEN (-6087 3133);
FORCEPROP 2 LAST CDS_LIB mstr_standard
J 0
(-6025 3125);
DISPLAY 0.723404 (-6025 3125);
PAINT MONO (-6025 3125);
DISPLAY INVISIBLE (-6025 3125);
FORCEPROP 1 LAST BODY_TYPE PLUMBING
J 0
(-6025 3175);
DISPLAY 0.872340 (-6025 3175);
PAINT GREEN (-6025 3175);
DISPLAY INVISIBLE (-6025 3175);
FORCEPROP 1 LAST HDL_TAP TRUE
J 0
(-5700 3000);
DISPLAY 0.872340 (-5700 3000);
DISPLAY INVISIBLE (-5700 3000);
FORCEPROP 1 LAST PATH I58
J 0
(-6027 3125);
DISPLAY 0.872340 (-6027 3125);
PAINT GREEN (-6027 3125);
DISPLAY INVISIBLE (-6027 3125);
FORCEADD TAP..1
(-6025 3175);
FORCEPROP 3 LASTPIN (-6075 3175) SIG_NAME M_L_CPU0_SB_DQ<26>
J 0
(-6065 3185);
DISPLAY 0.659574 (-6065 3185);
PAINT MONO (-6065 3185);
DISPLAY INVISIBLE (-6065 3185);
FORCEPROP 1 LASTPIN (-6075 3175) BN 26
J 0
(-6087 3183);
DISPLAY 0.489362 (-6087 3183);
PAINT GREEN (-6087 3183);
FORCEPROP 2 LAST CDS_LIB mstr_standard
J 0
(-6025 3175);
DISPLAY 0.723404 (-6025 3175);
PAINT MONO (-6025 3175);
DISPLAY INVISIBLE (-6025 3175);
FORCEPROP 1 LAST BODY_TYPE PLUMBING
J 0
(-6025 3225);
DISPLAY 0.872340 (-6025 3225);
PAINT GREEN (-6025 3225);
DISPLAY INVISIBLE (-6025 3225);
FORCEPROP 1 LAST HDL_TAP TRUE
J 0
(-5700 3050);
DISPLAY 0.872340 (-5700 3050);
DISPLAY INVISIBLE (-5700 3050);
FORCEPROP 1 LAST PATH I59
J 0
(-6027 3175);
DISPLAY 0.872340 (-6027 3175);
PAINT GREEN (-6027 3175);
DISPLAY INVISIBLE (-6027 3175);
FORCEADD OFFPAGE..1
(-8525 2575);
FORCEPROP 2 LAST $XR0 97 
J 0
(-8746 2575);
DISPLAY 0.638298 (-8746 2575);
PAINT MONO (-8746 2575);
FORCEPROP 2 LAST CDS_LIB mstr_standard
J 0
(-8525 2575);
DISPLAY 0.808511 (-8525 2575);
DISPLAY INVISIBLE (-8525 2575);
FORCEPROP 1 LAST OFFPAGE TRUE
J 0
(-8200 2450);
DISPLAY 0.872340 (-8200 2450);
PAINT GREEN (-8200 2450);
DISPLAY INVISIBLE (-8200 2450);
FORCEPROP 1 LAST COMMENT_BODY TRUE
J 0
(-8400 2475);
DISPLAY 0.872340 (-8400 2475);
PAINT GREEN (-8400 2475);
DISPLAY INVISIBLE (-8400 2475);
FORCEPROP 2 LAST PATH I6
J 0
(-8775 2625);
DISPLAY 1.021277 (-8775 2625);
DISPLAY INVISIBLE (-8775 2625);
FORCEADD TAP..1
(-6025 3225);
FORCEPROP 3 LASTPIN (-6075 3225) SIG_NAME M_L_CPU0_SB_DQ<27>
J 0
(-6065 3235);
DISPLAY 0.659574 (-6065 3235);
PAINT MONO (-6065 3235);
DISPLAY INVISIBLE (-6065 3235);
FORCEPROP 1 LASTPIN (-6075 3225) BN 27
J 0
(-6087 3233);
DISPLAY 0.489362 (-6087 3233);
PAINT GREEN (-6087 3233);
FORCEPROP 2 LAST CDS_LIB mstr_standard
J 0
(-6025 3225);
DISPLAY 0.723404 (-6025 3225);
PAINT MONO (-6025 3225);
DISPLAY INVISIBLE (-6025 3225);
FORCEPROP 1 LAST BODY_TYPE PLUMBING
J 0
(-6025 3275);
DISPLAY 0.872340 (-6025 3275);
PAINT GREEN (-6025 3275);
DISPLAY INVISIBLE (-6025 3275);
FORCEPROP 1 LAST HDL_TAP TRUE
J 0
(-5700 3100);
DISPLAY 0.872340 (-5700 3100);
DISPLAY INVISIBLE (-5700 3100);
FORCEPROP 1 LAST PATH I60
J 0
(-6027 3225);
DISPLAY 0.872340 (-6027 3225);
PAINT GREEN (-6027 3225);
DISPLAY INVISIBLE (-6027 3225);
FORCEADD TAP..1
(-6025 3275);
FORCEPROP 3 LASTPIN (-6075 3275) SIG_NAME M_L_CPU0_SB_DQ<28>
J 0
(-6065 3285);
DISPLAY 0.659574 (-6065 3285);
PAINT MONO (-6065 3285);
DISPLAY INVISIBLE (-6065 3285);
FORCEPROP 1 LASTPIN (-6075 3275) BN 28
J 0
(-6087 3283);
DISPLAY 0.489362 (-6087 3283);
PAINT GREEN (-6087 3283);
FORCEPROP 2 LAST CDS_LIB mstr_standard
J 0
(-6025 3275);
DISPLAY 0.723404 (-6025 3275);
PAINT MONO (-6025 3275);
DISPLAY INVISIBLE (-6025 3275);
FORCEPROP 1 LAST BODY_TYPE PLUMBING
J 0
(-6025 3325);
DISPLAY 0.872340 (-6025 3325);
PAINT GREEN (-6025 3325);
DISPLAY INVISIBLE (-6025 3325);
FORCEPROP 1 LAST HDL_TAP TRUE
J 0
(-5700 3150);
DISPLAY 0.872340 (-5700 3150);
DISPLAY INVISIBLE (-5700 3150);
FORCEPROP 1 LAST PATH I61
J 0
(-6027 3275);
DISPLAY 0.872340 (-6027 3275);
PAINT GREEN (-6027 3275);
DISPLAY INVISIBLE (-6027 3275);
FORCEADD TAP..1
(-6025 3325);
FORCEPROP 3 LASTPIN (-6075 3325) SIG_NAME M_L_CPU0_SB_DQ<29>
J 0
(-6065 3335);
DISPLAY 0.659574 (-6065 3335);
PAINT MONO (-6065 3335);
DISPLAY INVISIBLE (-6065 3335);
FORCEPROP 1 LASTPIN (-6075 3325) BN 29
J 0
(-6087 3333);
DISPLAY 0.489362 (-6087 3333);
PAINT GREEN (-6087 3333);
FORCEPROP 2 LAST CDS_LIB mstr_standard
J 0
(-6025 3325);
DISPLAY 0.723404 (-6025 3325);
PAINT MONO (-6025 3325);
DISPLAY INVISIBLE (-6025 3325);
FORCEPROP 1 LAST BODY_TYPE PLUMBING
J 0
(-6025 3375);
DISPLAY 0.872340 (-6025 3375);
PAINT GREEN (-6025 3375);
DISPLAY INVISIBLE (-6025 3375);
FORCEPROP 1 LAST HDL_TAP TRUE
J 0
(-5700 3200);
DISPLAY 0.872340 (-5700 3200);
DISPLAY INVISIBLE (-5700 3200);
FORCEPROP 1 LAST PATH I62
J 0
(-6027 3325);
DISPLAY 0.872340 (-6027 3325);
PAINT GREEN (-6027 3325);
DISPLAY INVISIBLE (-6027 3325);
FORCEADD TAP..1
(-6025 3375);
FORCEPROP 3 LASTPIN (-6075 3375) SIG_NAME M_L_CPU0_SB_DQ<30>
J 0
(-6065 3385);
DISPLAY 0.659574 (-6065 3385);
PAINT MONO (-6065 3385);
DISPLAY INVISIBLE (-6065 3385);
FORCEPROP 1 LASTPIN (-6075 3375) BN 30
J 0
(-6087 3383);
DISPLAY 0.489362 (-6087 3383);
PAINT GREEN (-6087 3383);
FORCEPROP 2 LAST CDS_LIB mstr_standard
J 0
(-6025 3375);
DISPLAY 0.723404 (-6025 3375);
PAINT MONO (-6025 3375);
DISPLAY INVISIBLE (-6025 3375);
FORCEPROP 1 LAST BODY_TYPE PLUMBING
J 0
(-6025 3425);
DISPLAY 0.872340 (-6025 3425);
PAINT GREEN (-6025 3425);
DISPLAY INVISIBLE (-6025 3425);
FORCEPROP 1 LAST HDL_TAP TRUE
J 0
(-5700 3250);
DISPLAY 0.872340 (-5700 3250);
DISPLAY INVISIBLE (-5700 3250);
FORCEPROP 1 LAST PATH I63
J 0
(-6027 3375);
DISPLAY 0.872340 (-6027 3375);
PAINT GREEN (-6027 3375);
DISPLAY INVISIBLE (-6027 3375);
FORCEADD OFFPAGE..5
(-8150 2725);
FORCEPROP 2 LAST $XR0 21 
J 0
(-8374 2725);
DISPLAY 0.638298 (-8374 2725);
PAINT MONO (-8374 2725);
FORCEPROP 2 LAST CDS_LIB mstr_standard
J 0
(-8150 2725);
DISPLAY INVISIBLE (-8150 2725);
FORCEPROP 1 LAST OFFPAGE TRUE
J 0
(-7825 2600);
DISPLAY 0.872340 (-7825 2600);
PAINT GREEN (-7825 2600);
DISPLAY INVISIBLE (-7825 2600);
FORCEPROP 1 LAST COMMENT_BODY TRUE
J 0
(-8050 2650);
DISPLAY 0.872340 (-8050 2650);
PAINT GREEN (-8050 2650);
DISPLAY INVISIBLE (-8050 2650);
FORCEPROP 2 LAST PATH I7
J 0
(-8100 2800);
DISPLAY 1.021277 (-8100 2800);
DISPLAY INVISIBLE (-8100 2800);
FORCEADD TAP..1
R 2
(-7725 3425);
FORCEPROP 3 LASTPIN (-7675 3425) SIG_NAME M_L_CPU0_SA_CB<2>
J 0
(-7665 3435);
DISPLAY 0.659574 (-7665 3435);
PAINT MONO (-7665 3435);
DISPLAY INVISIBLE (-7665 3435);
FORCEPROP 1 LASTPIN (-7675 3425) BN 2
J 2
(-7663 3433);
DISPLAY 0.489362 (-7663 3433);
PAINT GREEN (-7663 3433);
FORCEPROP 2 LAST CDS_LIB mstr_standard
J 0
(-7725 3425);
DISPLAY 0.723404 (-7725 3425);
PAINT MONO (-7725 3425);
DISPLAY INVISIBLE (-7725 3425);
FORCEPROP 1 LAST BODY_TYPE PLUMBING
J 2
(-7725 3475);
DISPLAY 0.872340 (-7725 3475);
PAINT GREEN (-7725 3475);
DISPLAY INVISIBLE (-7725 3475);
FORCEPROP 1 LAST HDL_TAP TRUE
J 2
(-8050 3300);
DISPLAY 0.872340 (-8050 3300);
DISPLAY INVISIBLE (-8050 3300);
FORCEPROP 1 LAST PATH I71
J 2
(-7723 3425);
DISPLAY 0.872340 (-7723 3425);
PAINT GREEN (-7723 3425);
DISPLAY INVISIBLE (-7723 3425);
FORCEADD TAP..1
R 2
(-7725 3475);
FORCEPROP 3 LASTPIN (-7675 3475) SIG_NAME M_L_CPU0_SA_CB<3>
J 0
(-7665 3485);
DISPLAY 0.659574 (-7665 3485);
PAINT MONO (-7665 3485);
DISPLAY INVISIBLE (-7665 3485);
FORCEPROP 1 LASTPIN (-7675 3475) BN 3
J 2
(-7663 3483);
DISPLAY 0.489362 (-7663 3483);
PAINT GREEN (-7663 3483);
FORCEPROP 2 LAST CDS_LIB mstr_standard
J 0
(-7725 3475);
DISPLAY 0.723404 (-7725 3475);
PAINT MONO (-7725 3475);
DISPLAY INVISIBLE (-7725 3475);
FORCEPROP 1 LAST BODY_TYPE PLUMBING
J 2
(-7725 3525);
DISPLAY 0.872340 (-7725 3525);
PAINT GREEN (-7725 3525);
DISPLAY INVISIBLE (-7725 3525);
FORCEPROP 1 LAST HDL_TAP TRUE
J 2
(-8050 3350);
DISPLAY 0.872340 (-8050 3350);
DISPLAY INVISIBLE (-8050 3350);
FORCEPROP 1 LAST PATH I72
J 2
(-7723 3475);
DISPLAY 0.872340 (-7723 3475);
PAINT GREEN (-7723 3475);
DISPLAY INVISIBLE (-7723 3475);
FORCEADD TAP..1
R 2
(-7725 3575);
FORCEPROP 3 LASTPIN (-7675 3575) SIG_NAME M_L_CPU0_SA_CB<5>
J 0
(-7665 3585);
DISPLAY 0.659574 (-7665 3585);
PAINT MONO (-7665 3585);
DISPLAY INVISIBLE (-7665 3585);
FORCEPROP 1 LASTPIN (-7675 3575) BN 5
J 2
(-7663 3583);
DISPLAY 0.489362 (-7663 3583);
PAINT GREEN (-7663 3583);
FORCEPROP 2 LAST CDS_LIB mstr_standard
J 0
(-7725 3575);
DISPLAY 0.723404 (-7725 3575);
PAINT MONO (-7725 3575);
DISPLAY INVISIBLE (-7725 3575);
FORCEPROP 1 LAST BODY_TYPE PLUMBING
J 2
(-7725 3625);
DISPLAY 0.872340 (-7725 3625);
PAINT GREEN (-7725 3625);
DISPLAY INVISIBLE (-7725 3625);
FORCEPROP 1 LAST HDL_TAP TRUE
J 2
(-8050 3450);
DISPLAY 0.872340 (-8050 3450);
DISPLAY INVISIBLE (-8050 3450);
FORCEPROP 1 LAST PATH I73
J 2
(-7723 3575);
DISPLAY 0.872340 (-7723 3575);
PAINT GREEN (-7723 3575);
DISPLAY INVISIBLE (-7723 3575);
FORCEADD TAP..1
R 2
(-7725 3625);
FORCEPROP 3 LASTPIN (-7675 3625) SIG_NAME M_L_CPU0_SA_CB<6>
J 0
(-7665 3635);
DISPLAY 0.659574 (-7665 3635);
PAINT MONO (-7665 3635);
DISPLAY INVISIBLE (-7665 3635);
FORCEPROP 1 LASTPIN (-7675 3625) BN 6
J 2
(-7663 3633);
DISPLAY 0.489362 (-7663 3633);
PAINT GREEN (-7663 3633);
FORCEPROP 2 LAST CDS_LIB mstr_standard
J 0
(-7725 3625);
DISPLAY 0.723404 (-7725 3625);
PAINT MONO (-7725 3625);
DISPLAY INVISIBLE (-7725 3625);
FORCEPROP 1 LAST BODY_TYPE PLUMBING
J 2
(-7725 3675);
DISPLAY 0.872340 (-7725 3675);
PAINT GREEN (-7725 3675);
DISPLAY INVISIBLE (-7725 3675);
FORCEPROP 1 LAST HDL_TAP TRUE
J 2
(-8050 3500);
DISPLAY 0.872340 (-8050 3500);
DISPLAY INVISIBLE (-8050 3500);
FORCEPROP 1 LAST PATH I74
J 2
(-7723 3625);
DISPLAY 0.872340 (-7723 3625);
PAINT GREEN (-7723 3625);
DISPLAY INVISIBLE (-7723 3625);
FORCEADD TAP..1
R 2
(-7725 3525);
FORCEPROP 3 LASTPIN (-7675 3525) SIG_NAME M_L_CPU0_SA_CB<4>
J 0
(-7665 3535);
DISPLAY 0.659574 (-7665 3535);
PAINT MONO (-7665 3535);
DISPLAY INVISIBLE (-7665 3535);
FORCEPROP 1 LASTPIN (-7675 3525) BN 4
J 2
(-7663 3533);
DISPLAY 0.489362 (-7663 3533);
PAINT GREEN (-7663 3533);
FORCEPROP 2 LAST CDS_LIB mstr_standard
J 0
(-7725 3525);
DISPLAY 0.723404 (-7725 3525);
PAINT MONO (-7725 3525);
DISPLAY INVISIBLE (-7725 3525);
FORCEPROP 1 LAST BODY_TYPE PLUMBING
J 2
(-7725 3575);
DISPLAY 0.872340 (-7725 3575);
PAINT GREEN (-7725 3575);
DISPLAY INVISIBLE (-7725 3575);
FORCEPROP 1 LAST HDL_TAP TRUE
J 2
(-8050 3400);
DISPLAY 0.872340 (-8050 3400);
DISPLAY INVISIBLE (-8050 3400);
FORCEPROP 1 LAST PATH I75
J 2
(-7723 3525);
DISPLAY 0.872340 (-7723 3525);
PAINT GREEN (-7723 3525);
DISPLAY INVISIBLE (-7723 3525);
FORCEADD TAP..1
R 2
(-7725 3675);
FORCEPROP 3 LASTPIN (-7675 3675) SIG_NAME M_L_CPU0_SA_CB<7>
J 0
(-7665 3685);
DISPLAY 0.659574 (-7665 3685);
PAINT MONO (-7665 3685);
DISPLAY INVISIBLE (-7665 3685);
FORCEPROP 1 LASTPIN (-7675 3675) BN 7
J 2
(-7663 3683);
DISPLAY 0.489362 (-7663 3683);
PAINT GREEN (-7663 3683);
FORCEPROP 2 LAST CDS_LIB mstr_standard
J 0
(-7725 3675);
DISPLAY 0.723404 (-7725 3675);
PAINT MONO (-7725 3675);
DISPLAY INVISIBLE (-7725 3675);
FORCEPROP 1 LAST BODY_TYPE PLUMBING
J 2
(-7725 3725);
DISPLAY 0.872340 (-7725 3725);
PAINT GREEN (-7725 3725);
DISPLAY INVISIBLE (-7725 3725);
FORCEPROP 1 LAST HDL_TAP TRUE
J 2
(-8050 3550);
DISPLAY 0.872340 (-8050 3550);
DISPLAY INVISIBLE (-8050 3550);
FORCEPROP 1 LAST PATH I76
J 2
(-7723 3675);
DISPLAY 0.872340 (-7723 3675);
PAINT GREEN (-7723 3675);
DISPLAY INVISIBLE (-7723 3675);
FORCEADD TAP..1
R 2
(-7725 4375);
FORCEPROP 3 LASTPIN (-7675 4375) SIG_NAME M_L_CPU0_SB_CA<0>
J 0
(-7665 4385);
DISPLAY 0.659574 (-7665 4385);
PAINT MONO (-7665 4385);
DISPLAY INVISIBLE (-7665 4385);
FORCEPROP 1 LASTPIN (-7675 4375) BN 0
J 2
(-7663 4383);
DISPLAY 0.489362 (-7663 4383);
PAINT GREEN (-7663 4383);
FORCEPROP 2 LAST CDS_LIB mstr_standard
J 0
(-7725 4375);
DISPLAY 0.723404 (-7725 4375);
PAINT MONO (-7725 4375);
DISPLAY INVISIBLE (-7725 4375);
FORCEPROP 1 LAST BODY_TYPE PLUMBING
J 2
(-7725 4425);
DISPLAY 0.872340 (-7725 4425);
PAINT GREEN (-7725 4425);
DISPLAY INVISIBLE (-7725 4425);
FORCEPROP 1 LAST HDL_TAP TRUE
J 2
(-8050 4250);
DISPLAY 0.872340 (-8050 4250);
DISPLAY INVISIBLE (-8050 4250);
FORCEPROP 1 LAST PATH I77
J 2
(-7723 4375);
DISPLAY 0.872340 (-7723 4375);
PAINT GREEN (-7723 4375);
DISPLAY INVISIBLE (-7723 4375);
FORCEADD TAP..1
R 2
(-7725 4425);
FORCEPROP 3 LASTPIN (-7675 4425) SIG_NAME M_L_CPU0_SB_CA<1>
J 0
(-7665 4435);
DISPLAY 0.659574 (-7665 4435);
PAINT MONO (-7665 4435);
DISPLAY INVISIBLE (-7665 4435);
FORCEPROP 1 LASTPIN (-7675 4425) BN 1
J 2
(-7663 4433);
DISPLAY 0.489362 (-7663 4433);
PAINT GREEN (-7663 4433);
FORCEPROP 2 LAST CDS_LIB mstr_standard
J 0
(-7725 4425);
DISPLAY 0.723404 (-7725 4425);
PAINT MONO (-7725 4425);
DISPLAY INVISIBLE (-7725 4425);
FORCEPROP 1 LAST BODY_TYPE PLUMBING
J 2
(-7725 4475);
DISPLAY 0.872340 (-7725 4475);
PAINT GREEN (-7725 4475);
DISPLAY INVISIBLE (-7725 4475);
FORCEPROP 1 LAST HDL_TAP TRUE
J 2
(-8050 4300);
DISPLAY 0.872340 (-8050 4300);
DISPLAY INVISIBLE (-8050 4300);
FORCEPROP 1 LAST PATH I78
J 2
(-7723 4425);
DISPLAY 0.872340 (-7723 4425);
PAINT GREEN (-7723 4425);
DISPLAY INVISIBLE (-7723 4425);
FORCEADD TAP..1
R 2
(-7725 4475);
FORCEPROP 3 LASTPIN (-7675 4475) SIG_NAME M_L_CPU0_SB_CA<2>
J 0
(-7665 4485);
DISPLAY 0.659574 (-7665 4485);
PAINT MONO (-7665 4485);
DISPLAY INVISIBLE (-7665 4485);
FORCEPROP 1 LASTPIN (-7675 4475) BN 2
J 2
(-7663 4483);
DISPLAY 0.489362 (-7663 4483);
PAINT GREEN (-7663 4483);
FORCEPROP 2 LAST CDS_LIB mstr_standard
J 0
(-7725 4475);
DISPLAY 0.723404 (-7725 4475);
PAINT MONO (-7725 4475);
DISPLAY INVISIBLE (-7725 4475);
FORCEPROP 1 LAST BODY_TYPE PLUMBING
J 2
(-7725 4525);
DISPLAY 0.872340 (-7725 4525);
PAINT GREEN (-7725 4525);
DISPLAY INVISIBLE (-7725 4525);
FORCEPROP 1 LAST HDL_TAP TRUE
J 2
(-8050 4350);
DISPLAY 0.872340 (-8050 4350);
DISPLAY INVISIBLE (-8050 4350);
FORCEPROP 1 LAST PATH I79
J 2
(-7723 4475);
DISPLAY 0.872340 (-7723 4475);
PAINT GREEN (-7723 4475);
DISPLAY INVISIBLE (-7723 4475);
FORCEADD OFFPAGE..1
(-8150 2775);
FORCEPROP 2 LAST $XR0 21 
J 0
(-8401 2775);
DISPLAY 0.638298 (-8401 2775);
PAINT MONO (-8401 2775);
FORCEPROP 2 LAST CDS_LIB mstr_standard
J 0
(-8150 2775);
DISPLAY 0.808511 (-8150 2775);
DISPLAY INVISIBLE (-8150 2775);
FORCEPROP 1 LAST OFFPAGE TRUE
J 0
(-7825 2650);
DISPLAY 0.872340 (-7825 2650);
PAINT GREEN (-7825 2650);
DISPLAY INVISIBLE (-7825 2650);
FORCEPROP 1 LAST COMMENT_BODY TRUE
J 0
(-8025 2675);
DISPLAY 0.872340 (-8025 2675);
PAINT GREEN (-8025 2675);
DISPLAY INVISIBLE (-8025 2675);
FORCEPROP 2 LAST PATH I8
J 0
(-8575 2825);
DISPLAY 1.021277 (-8575 2825);
DISPLAY INVISIBLE (-8575 2825);
FORCEADD TAP..1
R 2
(-7725 4525);
FORCEPROP 3 LASTPIN (-7675 4525) SIG_NAME M_L_CPU0_SB_CA<3>
J 0
(-7665 4535);
DISPLAY 0.659574 (-7665 4535);
PAINT MONO (-7665 4535);
DISPLAY INVISIBLE (-7665 4535);
FORCEPROP 1 LASTPIN (-7675 4525) BN 3
J 2
(-7663 4533);
DISPLAY 0.489362 (-7663 4533);
PAINT GREEN (-7663 4533);
FORCEPROP 2 LAST CDS_LIB mstr_standard
J 0
(-7725 4525);
DISPLAY 0.723404 (-7725 4525);
PAINT MONO (-7725 4525);
DISPLAY INVISIBLE (-7725 4525);
FORCEPROP 1 LAST BODY_TYPE PLUMBING
J 2
(-7725 4575);
DISPLAY 0.872340 (-7725 4575);
PAINT GREEN (-7725 4575);
DISPLAY INVISIBLE (-7725 4575);
FORCEPROP 1 LAST HDL_TAP TRUE
J 2
(-8050 4400);
DISPLAY 0.872340 (-8050 4400);
DISPLAY INVISIBLE (-8050 4400);
FORCEPROP 1 LAST PATH I80
J 2
(-7723 4525);
DISPLAY 0.872340 (-7723 4525);
PAINT GREEN (-7723 4525);
DISPLAY INVISIBLE (-7723 4525);
FORCEADD TAP..1
R 2
(-7725 4575);
FORCEPROP 3 LASTPIN (-7675 4575) SIG_NAME M_L_CPU0_SB_CA<4>
J 0
(-7665 4585);
DISPLAY 0.659574 (-7665 4585);
PAINT MONO (-7665 4585);
DISPLAY INVISIBLE (-7665 4585);
FORCEPROP 1 LASTPIN (-7675 4575) BN 4
J 2
(-7663 4583);
DISPLAY 0.489362 (-7663 4583);
PAINT GREEN (-7663 4583);
FORCEPROP 2 LAST CDS_LIB mstr_standard
J 0
(-7725 4575);
DISPLAY 0.723404 (-7725 4575);
PAINT MONO (-7725 4575);
DISPLAY INVISIBLE (-7725 4575);
FORCEPROP 1 LAST BODY_TYPE PLUMBING
J 2
(-7725 4625);
DISPLAY 0.872340 (-7725 4625);
PAINT GREEN (-7725 4625);
DISPLAY INVISIBLE (-7725 4625);
FORCEPROP 1 LAST HDL_TAP TRUE
J 2
(-8050 4450);
DISPLAY 0.872340 (-8050 4450);
DISPLAY INVISIBLE (-8050 4450);
FORCEPROP 1 LAST PATH I81
J 2
(-7723 4575);
DISPLAY 0.872340 (-7723 4575);
PAINT GREEN (-7723 4575);
DISPLAY INVISIBLE (-7723 4575);
FORCEADD TAP..1
R 2
(-7725 4675);
FORCEPROP 3 LASTPIN (-7675 4675) SIG_NAME M_L_CPU0_SB_CA<6>
J 0
(-7665 4685);
DISPLAY 0.659574 (-7665 4685);
PAINT MONO (-7665 4685);
DISPLAY INVISIBLE (-7665 4685);
FORCEPROP 1 LASTPIN (-7675 4675) BN 6
J 2
(-7663 4683);
DISPLAY 0.489362 (-7663 4683);
PAINT GREEN (-7663 4683);
FORCEPROP 2 LAST CDS_LIB mstr_standard
J 0
(-7725 4675);
DISPLAY 0.723404 (-7725 4675);
PAINT MONO (-7725 4675);
DISPLAY INVISIBLE (-7725 4675);
FORCEPROP 1 LAST BODY_TYPE PLUMBING
J 2
(-7725 4725);
DISPLAY 0.872340 (-7725 4725);
PAINT GREEN (-7725 4725);
DISPLAY INVISIBLE (-7725 4725);
FORCEPROP 1 LAST HDL_TAP TRUE
J 2
(-8050 4550);
DISPLAY 0.872340 (-8050 4550);
DISPLAY INVISIBLE (-8050 4550);
FORCEPROP 1 LAST PATH I82
J 2
(-7723 4675);
DISPLAY 0.872340 (-7723 4675);
PAINT GREEN (-7723 4675);
DISPLAY INVISIBLE (-7723 4675);
FORCEADD TAP..1
R 2
(-7725 4625);
FORCEPROP 3 LASTPIN (-7675 4625) SIG_NAME M_L_CPU0_SB_CA<5>
J 0
(-7665 4635);
DISPLAY 0.659574 (-7665 4635);
PAINT MONO (-7665 4635);
DISPLAY INVISIBLE (-7665 4635);
FORCEPROP 1 LASTPIN (-7675 4625) BN 5
J 2
(-7663 4633);
DISPLAY 0.489362 (-7663 4633);
PAINT GREEN (-7663 4633);
FORCEPROP 2 LAST CDS_LIB mstr_standard
J 0
(-7725 4625);
DISPLAY 0.723404 (-7725 4625);
PAINT MONO (-7725 4625);
DISPLAY INVISIBLE (-7725 4625);
FORCEPROP 1 LAST BODY_TYPE PLUMBING
J 2
(-7725 4675);
DISPLAY 0.872340 (-7725 4675);
PAINT GREEN (-7725 4675);
DISPLAY INVISIBLE (-7725 4675);
FORCEPROP 1 LAST HDL_TAP TRUE
J 2
(-8050 4500);
DISPLAY 0.872340 (-8050 4500);
DISPLAY INVISIBLE (-8050 4500);
FORCEPROP 1 LAST PATH I83
J 2
(-7723 4625);
DISPLAY 0.872340 (-7723 4625);
PAINT GREEN (-7723 4625);
DISPLAY INVISIBLE (-7723 4625);
FORCEADD TAP..1
R 2
(-7725 4825);
FORCEPROP 3 LASTPIN (-7675 4825) SIG_NAME M_L_CPU0_SA_CA<1>
J 0
(-7665 4835);
DISPLAY 0.659574 (-7665 4835);
PAINT MONO (-7665 4835);
DISPLAY INVISIBLE (-7665 4835);
FORCEPROP 1 LASTPIN (-7675 4825) BN 1
J 2
(-7663 4833);
DISPLAY 0.489362 (-7663 4833);
PAINT GREEN (-7663 4833);
FORCEPROP 2 LAST CDS_LIB mstr_standard
J 0
(-7725 4825);
DISPLAY 0.723404 (-7725 4825);
PAINT MONO (-7725 4825);
DISPLAY INVISIBLE (-7725 4825);
FORCEPROP 1 LAST BODY_TYPE PLUMBING
J 2
(-7725 4875);
DISPLAY 0.872340 (-7725 4875);
PAINT GREEN (-7725 4875);
DISPLAY INVISIBLE (-7725 4875);
FORCEPROP 1 LAST HDL_TAP TRUE
J 2
(-8050 4700);
DISPLAY 0.872340 (-8050 4700);
DISPLAY INVISIBLE (-8050 4700);
FORCEPROP 1 LAST PATH I84
J 2
(-7723 4825);
DISPLAY 0.872340 (-7723 4825);
PAINT GREEN (-7723 4825);
DISPLAY INVISIBLE (-7723 4825);
FORCEADD TAP..1
R 2
(-7725 4875);
FORCEPROP 3 LASTPIN (-7675 4875) SIG_NAME M_L_CPU0_SA_CA<2>
J 0
(-7665 4885);
DISPLAY 0.659574 (-7665 4885);
PAINT MONO (-7665 4885);
DISPLAY INVISIBLE (-7665 4885);
FORCEPROP 1 LASTPIN (-7675 4875) BN 2
J 2
(-7663 4883);
DISPLAY 0.489362 (-7663 4883);
PAINT GREEN (-7663 4883);
FORCEPROP 2 LAST CDS_LIB mstr_standard
J 0
(-7725 4875);
DISPLAY 0.723404 (-7725 4875);
PAINT MONO (-7725 4875);
DISPLAY INVISIBLE (-7725 4875);
FORCEPROP 1 LAST BODY_TYPE PLUMBING
J 2
(-7725 4925);
DISPLAY 0.872340 (-7725 4925);
PAINT GREEN (-7725 4925);
DISPLAY INVISIBLE (-7725 4925);
FORCEPROP 1 LAST HDL_TAP TRUE
J 2
(-8050 4750);
DISPLAY 0.872340 (-8050 4750);
DISPLAY INVISIBLE (-8050 4750);
FORCEPROP 1 LAST PATH I85
J 2
(-7723 4875);
DISPLAY 0.872340 (-7723 4875);
PAINT GREEN (-7723 4875);
DISPLAY INVISIBLE (-7723 4875);
FORCEADD TAP..1
R 2
(-7725 4925);
FORCEPROP 3 LASTPIN (-7675 4925) SIG_NAME M_L_CPU0_SA_CA<3>
J 0
(-7665 4935);
DISPLAY 0.659574 (-7665 4935);
PAINT MONO (-7665 4935);
DISPLAY INVISIBLE (-7665 4935);
FORCEPROP 1 LASTPIN (-7675 4925) BN 3
J 2
(-7663 4933);
DISPLAY 0.489362 (-7663 4933);
PAINT GREEN (-7663 4933);
FORCEPROP 2 LAST CDS_LIB mstr_standard
J 0
(-7725 4925);
DISPLAY 0.723404 (-7725 4925);
PAINT MONO (-7725 4925);
DISPLAY INVISIBLE (-7725 4925);
FORCEPROP 1 LAST BODY_TYPE PLUMBING
J 2
(-7725 4975);
DISPLAY 0.872340 (-7725 4975);
PAINT GREEN (-7725 4975);
DISPLAY INVISIBLE (-7725 4975);
FORCEPROP 1 LAST HDL_TAP TRUE
J 2
(-8050 4800);
DISPLAY 0.872340 (-8050 4800);
DISPLAY INVISIBLE (-8050 4800);
FORCEPROP 1 LAST PATH I86
J 2
(-7723 4925);
DISPLAY 0.872340 (-7723 4925);
PAINT GREEN (-7723 4925);
DISPLAY INVISIBLE (-7723 4925);
FORCEADD TAP..1
R 2
(-7725 4775);
FORCEPROP 3 LASTPIN (-7675 4775) SIG_NAME M_L_CPU0_SA_CA<0>
J 0
(-7665 4785);
DISPLAY 0.659574 (-7665 4785);
PAINT MONO (-7665 4785);
DISPLAY INVISIBLE (-7665 4785);
FORCEPROP 1 LASTPIN (-7675 4775) BN 0
J 2
(-7663 4783);
DISPLAY 0.489362 (-7663 4783);
PAINT GREEN (-7663 4783);
FORCEPROP 2 LAST CDS_LIB mstr_standard
J 0
(-7725 4775);
DISPLAY 0.723404 (-7725 4775);
PAINT MONO (-7725 4775);
DISPLAY INVISIBLE (-7725 4775);
FORCEPROP 1 LAST BODY_TYPE PLUMBING
J 2
(-7725 4825);
DISPLAY 0.872340 (-7725 4825);
PAINT GREEN (-7725 4825);
DISPLAY INVISIBLE (-7725 4825);
FORCEPROP 1 LAST HDL_TAP TRUE
J 2
(-8050 4650);
DISPLAY 0.872340 (-8050 4650);
DISPLAY INVISIBLE (-8050 4650);
FORCEPROP 1 LAST PATH I87
J 2
(-7723 4775);
DISPLAY 0.872340 (-7723 4775);
PAINT GREEN (-7723 4775);
DISPLAY INVISIBLE (-7723 4775);
FORCEADD TAP..1
R 2
(-7725 5025);
FORCEPROP 3 LASTPIN (-7675 5025) SIG_NAME M_L_CPU0_SA_CA<5>
J 0
(-7665 5035);
DISPLAY 0.659574 (-7665 5035);
PAINT MONO (-7665 5035);
DISPLAY INVISIBLE (-7665 5035);
FORCEPROP 1 LASTPIN (-7675 5025) BN 5
J 2
(-7663 5033);
DISPLAY 0.489362 (-7663 5033);
PAINT GREEN (-7663 5033);
FORCEPROP 2 LAST CDS_LIB mstr_standard
J 0
(-7725 5025);
DISPLAY 0.723404 (-7725 5025);
PAINT MONO (-7725 5025);
DISPLAY INVISIBLE (-7725 5025);
FORCEPROP 1 LAST BODY_TYPE PLUMBING
J 2
(-7725 5075);
DISPLAY 0.872340 (-7725 5075);
PAINT GREEN (-7725 5075);
DISPLAY INVISIBLE (-7725 5075);
FORCEPROP 1 LAST HDL_TAP TRUE
J 2
(-8050 4900);
DISPLAY 0.872340 (-8050 4900);
DISPLAY INVISIBLE (-8050 4900);
FORCEPROP 1 LAST PATH I88
J 2
(-7723 5025);
DISPLAY 0.872340 (-7723 5025);
PAINT GREEN (-7723 5025);
DISPLAY INVISIBLE (-7723 5025);
FORCEADD TAP..1
R 2
(-7725 5075);
FORCEPROP 3 LASTPIN (-7675 5075) SIG_NAME M_L_CPU0_SA_CA<6>
J 0
(-7665 5085);
DISPLAY 0.659574 (-7665 5085);
PAINT MONO (-7665 5085);
DISPLAY INVISIBLE (-7665 5085);
FORCEPROP 1 LASTPIN (-7675 5075) BN 6
J 2
(-7663 5083);
DISPLAY 0.489362 (-7663 5083);
PAINT GREEN (-7663 5083);
FORCEPROP 2 LAST CDS_LIB mstr_standard
J 0
(-7725 5075);
DISPLAY 0.723404 (-7725 5075);
PAINT MONO (-7725 5075);
DISPLAY INVISIBLE (-7725 5075);
FORCEPROP 1 LAST BODY_TYPE PLUMBING
J 2
(-7725 5125);
DISPLAY 0.872340 (-7725 5125);
PAINT GREEN (-7725 5125);
DISPLAY INVISIBLE (-7725 5125);
FORCEPROP 1 LAST HDL_TAP TRUE
J 2
(-8050 4950);
DISPLAY 0.872340 (-8050 4950);
DISPLAY INVISIBLE (-8050 4950);
FORCEPROP 1 LAST PATH I89
J 2
(-7723 5075);
DISPLAY 0.872340 (-7723 5075);
PAINT GREEN (-7723 5075);
DISPLAY INVISIBLE (-7723 5075);
FORCEADD VCC_CORE..1
(-8500 3100);
FORCEPROP 3 LASTPIN (-8500 3050) SIG_NAME P3V3_AUX\g
J 0
(-8490 3060);
DISPLAY 0.659574 (-8490 3060);
PAINT MONO (-8490 3060);
DISPLAY INVISIBLE (-8490 3060);
FORCEPROP 1 LAST HDL_POWER P3V3_AUX
J 1
(-8500 3150);
DISPLAY 0.489362 (-8500 3150);
PAINT GREEN (-8500 3150);
FORCEPROP 2 LAST CDS_LIB mstr_symbols
J 0
(-8500 3100);
PAINT MONO (-8500 3100);
DISPLAY INVISIBLE (-8500 3100);
FORCEPROP 0 LAST VOLTAGE 3.3
J 0
(-8775 3250);
DISPLAY 1.021277 (-8775 3250);
PAINT SKYBLUE (-8775 3250);
DISPLAY INVISIBLE (-8775 3250);
FORCEPROP 2 LAST ROOM PVCCINFAON_CPU0_CTRL
J 0
(-8500 3200);
DISPLAY 0.808511 (-8500 3200);
PAINT RED (-8500 3200);
DISPLAY INVISIBLE (-8500 3200);
FORCEPROP 1 LAST PATH I9
J 0
(-8450 3125);
DISPLAY 0.872340 (-8450 3125);
PAINT AQUA (-8450 3125);
DISPLAY INVISIBLE (-8450 3125);
FORCEADD TAP..1
R 2
(-7725 4975);
FORCEPROP 3 LASTPIN (-7675 4975) SIG_NAME M_L_CPU0_SA_CA<4>
J 0
(-7665 4985);
DISPLAY 0.659574 (-7665 4985);
PAINT MONO (-7665 4985);
DISPLAY INVISIBLE (-7665 4985);
FORCEPROP 1 LASTPIN (-7675 4975) BN 4
J 2
(-7663 4983);
DISPLAY 0.489362 (-7663 4983);
PAINT GREEN (-7663 4983);
FORCEPROP 2 LAST CDS_LIB mstr_standard
J 0
(-7725 4975);
DISPLAY 0.723404 (-7725 4975);
PAINT MONO (-7725 4975);
DISPLAY INVISIBLE (-7725 4975);
FORCEPROP 1 LAST BODY_TYPE PLUMBING
J 2
(-7725 5025);
DISPLAY 0.872340 (-7725 5025);
PAINT GREEN (-7725 5025);
DISPLAY INVISIBLE (-7725 5025);
FORCEPROP 1 LAST HDL_TAP TRUE
J 2
(-8050 4850);
DISPLAY 0.872340 (-8050 4850);
DISPLAY INVISIBLE (-8050 4850);
FORCEPROP 1 LAST PATH I90
J 2
(-7723 4975);
DISPLAY 0.872340 (-7723 4975);
PAINT GREEN (-7723 4975);
DISPLAY INVISIBLE (-7723 4975);
FORCEADD TAP..1
(-6025 3425);
FORCEPROP 3 LASTPIN (-6075 3425) SIG_NAME M_L_CPU0_SB_DQ<31>
J 0
(-6065 3435);
DISPLAY 0.659574 (-6065 3435);
PAINT MONO (-6065 3435);
DISPLAY INVISIBLE (-6065 3435);
FORCEPROP 1 LASTPIN (-6075 3425) BN 31
J 0
(-6087 3433);
DISPLAY 0.489362 (-6087 3433);
PAINT GREEN (-6087 3433);
FORCEPROP 2 LAST CDS_LIB mstr_standard
J 0
(-6025 3425);
DISPLAY 0.723404 (-6025 3425);
PAINT MONO (-6025 3425);
DISPLAY INVISIBLE (-6025 3425);
FORCEPROP 1 LAST BODY_TYPE PLUMBING
J 0
(-6025 3475);
DISPLAY 0.872340 (-6025 3475);
PAINT GREEN (-6025 3475);
DISPLAY INVISIBLE (-6025 3475);
FORCEPROP 1 LAST HDL_TAP TRUE
J 0
(-5700 3300);
DISPLAY 0.872340 (-5700 3300);
DISPLAY INVISIBLE (-5700 3300);
FORCEPROP 1 LAST PATH I91
J 0
(-6027 3425);
DISPLAY 0.872340 (-6027 3425);
PAINT GREEN (-6027 3425);
DISPLAY INVISIBLE (-6027 3425);
FORCEADD TAP..1
(-6025 3525);
FORCEPROP 3 LASTPIN (-6075 3525) SIG_NAME M_L_CPU0_SA_DQ<0>
J 0
(-6065 3535);
DISPLAY 0.659574 (-6065 3535);
PAINT MONO (-6065 3535);
DISPLAY INVISIBLE (-6065 3535);
FORCEPROP 1 LASTPIN (-6075 3525) BN 0
J 0
(-6087 3533);
DISPLAY 0.489362 (-6087 3533);
PAINT GREEN (-6087 3533);
FORCEPROP 2 LAST CDS_LIB mstr_standard
J 0
(-6025 3525);
DISPLAY 0.723404 (-6025 3525);
PAINT MONO (-6025 3525);
DISPLAY INVISIBLE (-6025 3525);
FORCEPROP 1 LAST BODY_TYPE PLUMBING
J 0
(-6025 3575);
DISPLAY 0.872340 (-6025 3575);
PAINT GREEN (-6025 3575);
DISPLAY INVISIBLE (-6025 3575);
FORCEPROP 1 LAST HDL_TAP TRUE
J 0
(-5700 3400);
DISPLAY 0.872340 (-5700 3400);
DISPLAY INVISIBLE (-5700 3400);
FORCEPROP 1 LAST PATH I92
J 0
(-6027 3525);
DISPLAY 0.872340 (-6027 3525);
PAINT GREEN (-6027 3525);
DISPLAY INVISIBLE (-6027 3525);
FORCEADD TAP..1
(-6025 3575);
FORCEPROP 3 LASTPIN (-6075 3575) SIG_NAME M_L_CPU0_SA_DQ<1>
J 0
(-6065 3585);
DISPLAY 0.659574 (-6065 3585);
PAINT MONO (-6065 3585);
DISPLAY INVISIBLE (-6065 3585);
FORCEPROP 1 LASTPIN (-6075 3575) BN 1
J 0
(-6087 3583);
DISPLAY 0.489362 (-6087 3583);
PAINT GREEN (-6087 3583);
FORCEPROP 2 LAST CDS_LIB mstr_standard
J 0
(-6025 3575);
DISPLAY 0.723404 (-6025 3575);
PAINT MONO (-6025 3575);
DISPLAY INVISIBLE (-6025 3575);
FORCEPROP 1 LAST BODY_TYPE PLUMBING
J 0
(-6025 3625);
DISPLAY 0.872340 (-6025 3625);
PAINT GREEN (-6025 3625);
DISPLAY INVISIBLE (-6025 3625);
FORCEPROP 1 LAST HDL_TAP TRUE
J 0
(-5700 3450);
DISPLAY 0.872340 (-5700 3450);
DISPLAY INVISIBLE (-5700 3450);
FORCEPROP 1 LAST PATH I93
J 0
(-6027 3575);
DISPLAY 0.872340 (-6027 3575);
PAINT GREEN (-6027 3575);
DISPLAY INVISIBLE (-6027 3575);
FORCEADD TAP..1
(-6025 3625);
FORCEPROP 3 LASTPIN (-6075 3625) SIG_NAME M_L_CPU0_SA_DQ<2>
J 0
(-6065 3635);
DISPLAY 0.659574 (-6065 3635);
PAINT MONO (-6065 3635);
DISPLAY INVISIBLE (-6065 3635);
FORCEPROP 1 LASTPIN (-6075 3625) BN 2
J 0
(-6087 3633);
DISPLAY 0.489362 (-6087 3633);
PAINT GREEN (-6087 3633);
FORCEPROP 2 LAST CDS_LIB mstr_standard
J 0
(-6025 3625);
DISPLAY 0.723404 (-6025 3625);
PAINT MONO (-6025 3625);
DISPLAY INVISIBLE (-6025 3625);
FORCEPROP 1 LAST BODY_TYPE PLUMBING
J 0
(-6025 3675);
DISPLAY 0.872340 (-6025 3675);
PAINT GREEN (-6025 3675);
DISPLAY INVISIBLE (-6025 3675);
FORCEPROP 1 LAST HDL_TAP TRUE
J 0
(-5700 3500);
DISPLAY 0.872340 (-5700 3500);
DISPLAY INVISIBLE (-5700 3500);
FORCEPROP 1 LAST PATH I94
J 0
(-6027 3625);
DISPLAY 0.872340 (-6027 3625);
PAINT GREEN (-6027 3625);
DISPLAY INVISIBLE (-6027 3625);
FORCEADD TAP..1
(-6025 3675);
FORCEPROP 3 LASTPIN (-6075 3675) SIG_NAME M_L_CPU0_SA_DQ<3>
J 0
(-6065 3685);
DISPLAY 0.659574 (-6065 3685);
PAINT MONO (-6065 3685);
DISPLAY INVISIBLE (-6065 3685);
FORCEPROP 1 LASTPIN (-6075 3675) BN 3
J 0
(-6087 3683);
DISPLAY 0.489362 (-6087 3683);
PAINT GREEN (-6087 3683);
FORCEPROP 2 LAST CDS_LIB mstr_standard
J 0
(-6025 3675);
DISPLAY 0.723404 (-6025 3675);
PAINT MONO (-6025 3675);
DISPLAY INVISIBLE (-6025 3675);
FORCEPROP 1 LAST BODY_TYPE PLUMBING
J 0
(-6025 3725);
DISPLAY 0.872340 (-6025 3725);
PAINT GREEN (-6025 3725);
DISPLAY INVISIBLE (-6025 3725);
FORCEPROP 1 LAST HDL_TAP TRUE
J 0
(-5700 3550);
DISPLAY 0.872340 (-5700 3550);
DISPLAY INVISIBLE (-5700 3550);
FORCEPROP 1 LAST PATH I95
J 0
(-6027 3675);
DISPLAY 0.872340 (-6027 3675);
PAINT GREEN (-6027 3675);
DISPLAY INVISIBLE (-6027 3675);
FORCEADD TAP..1
(-6025 3725);
FORCEPROP 3 LASTPIN (-6075 3725) SIG_NAME M_L_CPU0_SA_DQ<4>
J 0
(-6065 3735);
DISPLAY 0.659574 (-6065 3735);
PAINT MONO (-6065 3735);
DISPLAY INVISIBLE (-6065 3735);
FORCEPROP 1 LASTPIN (-6075 3725) BN 4
J 0
(-6087 3733);
DISPLAY 0.489362 (-6087 3733);
PAINT GREEN (-6087 3733);
FORCEPROP 2 LAST CDS_LIB mstr_standard
J 0
(-6025 3725);
DISPLAY 0.723404 (-6025 3725);
PAINT MONO (-6025 3725);
DISPLAY INVISIBLE (-6025 3725);
FORCEPROP 1 LAST BODY_TYPE PLUMBING
J 0
(-6025 3775);
DISPLAY 0.872340 (-6025 3775);
PAINT GREEN (-6025 3775);
DISPLAY INVISIBLE (-6025 3775);
FORCEPROP 1 LAST HDL_TAP TRUE
J 0
(-5700 3600);
DISPLAY 0.872340 (-5700 3600);
DISPLAY INVISIBLE (-5700 3600);
FORCEPROP 1 LAST PATH I96
J 0
(-6027 3725);
DISPLAY 0.872340 (-6027 3725);
PAINT GREEN (-6027 3725);
DISPLAY INVISIBLE (-6027 3725);
FORCEADD TAP..1
(-6025 3775);
FORCEPROP 3 LASTPIN (-6075 3775) SIG_NAME M_L_CPU0_SA_DQ<5>
J 0
(-6065 3785);
DISPLAY 0.659574 (-6065 3785);
PAINT MONO (-6065 3785);
DISPLAY INVISIBLE (-6065 3785);
FORCEPROP 1 LASTPIN (-6075 3775) BN 5
J 0
(-6087 3783);
DISPLAY 0.489362 (-6087 3783);
PAINT GREEN (-6087 3783);
FORCEPROP 2 LAST CDS_LIB mstr_standard
J 0
(-6025 3775);
DISPLAY 0.723404 (-6025 3775);
PAINT MONO (-6025 3775);
DISPLAY INVISIBLE (-6025 3775);
FORCEPROP 1 LAST BODY_TYPE PLUMBING
J 0
(-6025 3825);
DISPLAY 0.872340 (-6025 3825);
PAINT GREEN (-6025 3825);
DISPLAY INVISIBLE (-6025 3825);
FORCEPROP 1 LAST HDL_TAP TRUE
J 0
(-5700 3650);
DISPLAY 0.872340 (-5700 3650);
DISPLAY INVISIBLE (-5700 3650);
FORCEPROP 1 LAST PATH I97
J 0
(-6027 3775);
DISPLAY 0.872340 (-6027 3775);
PAINT GREEN (-6027 3775);
DISPLAY INVISIBLE (-6027 3775);
FORCEADD TAP..1
(-6025 3825);
FORCEPROP 3 LASTPIN (-6075 3825) SIG_NAME M_L_CPU0_SA_DQ<6>
J 0
(-6065 3835);
DISPLAY 0.659574 (-6065 3835);
PAINT MONO (-6065 3835);
DISPLAY INVISIBLE (-6065 3835);
FORCEPROP 1 LASTPIN (-6075 3825) BN 6
J 0
(-6087 3833);
DISPLAY 0.489362 (-6087 3833);
PAINT GREEN (-6087 3833);
FORCEPROP 2 LAST CDS_LIB mstr_standard
J 0
(-6025 3825);
DISPLAY 0.723404 (-6025 3825);
PAINT MONO (-6025 3825);
DISPLAY INVISIBLE (-6025 3825);
FORCEPROP 1 LAST BODY_TYPE PLUMBING
J 0
(-6025 3875);
DISPLAY 0.872340 (-6025 3875);
PAINT GREEN (-6025 3875);
DISPLAY INVISIBLE (-6025 3875);
FORCEPROP 1 LAST HDL_TAP TRUE
J 0
(-5700 3700);
DISPLAY 0.872340 (-5700 3700);
DISPLAY INVISIBLE (-5700 3700);
FORCEPROP 1 LAST PATH I98
J 0
(-6027 3825);
DISPLAY 0.872340 (-6027 3825);
PAINT GREEN (-6027 3825);
DISPLAY INVISIBLE (-6027 3825);
FORCEADD TAP..1
(-6025 3875);
FORCEPROP 3 LASTPIN (-6075 3875) SIG_NAME M_L_CPU0_SA_DQ<7>
J 0
(-6065 3885);
DISPLAY 0.659574 (-6065 3885);
PAINT MONO (-6065 3885);
DISPLAY INVISIBLE (-6065 3885);
FORCEPROP 1 LASTPIN (-6075 3875) BN 7
J 0
(-6087 3883);
DISPLAY 0.489362 (-6087 3883);
PAINT GREEN (-6087 3883);
FORCEPROP 2 LAST CDS_LIB mstr_standard
J 0
(-6025 3875);
DISPLAY 0.723404 (-6025 3875);
PAINT MONO (-6025 3875);
DISPLAY INVISIBLE (-6025 3875);
FORCEPROP 1 LAST BODY_TYPE PLUMBING
J 0
(-6025 3925);
DISPLAY 0.872340 (-6025 3925);
PAINT GREEN (-6025 3925);
DISPLAY INVISIBLE (-6025 3925);
FORCEPROP 1 LAST HDL_TAP TRUE
J 0
(-5700 3750);
DISPLAY 0.872340 (-5700 3750);
DISPLAY INVISIBLE (-5700 3750);
FORCEPROP 1 LAST PATH I99
J 0
(-6027 3875);
DISPLAY 0.872340 (-6027 3875);
PAINT GREEN (-6027 3875);
DISPLAY INVISIBLE (-6027 3875);
FORCEADD QUANTA_TITLE_BLOCK_C..1
(0 0);
FORCEPROP 0 LAST CDS_CON_LAST_MODIFIED Thu Sep 14 16:12:09 2023
J 0
(-1885 15);
DISPLAY INVISIBLE (-1885 15);
FORCEPROP 1 LAST CUSTOM_TXT_CDS <CON_LAST_MODIFIED>
J 0
(-1885 15);
DISPLAY 0.978723 (-1885 15);
FORCEPROP 2 LAST CUSTOM_TXT_CDS <XR_PAGE_TITLE>
J 0
(-7890 5250);
DISPLAY 0.638298 (-7890 5250);
PAINT PINK (-7890 5250);
DISPLAY INVISIBLE (-7890 5250);
FORCEPROP 1 LAST CUSTOM_TXT_CDS <NAME_2>
J 0
(-3175 50);
FORCEPROP 1 LAST CUSTOM_TXT_CDS <NAME_1>
J 0
(-3175 175);
FORCEPROP 1 LAST CUSTOM_TXT_CDS <Q_NUMBER>
J 0
(-1403 103);
DISPLAY 1.212766 (-1403 103);
FORCEPROP 1 LAST CUSTOM_TXT_CDS <Q_PROJ>
J 0
(-2382 102);
DISPLAY 1.212766 (-2382 102);
FORCEPROP 1 LAST CUSTOM_TXT_CDS <Q_REV>
J 0
(-184 103);
DISPLAY 1.212766 (-184 103);
FORCEPROP 1 LAST CUSTOM_TXT_CDS <CON_PAGE_NUM> OF <CON_TOTAL_PAGES>
J 0
(-446 18);
DISPLAY 0.978723 (-446 18);
FORCEPROP 1 LAST Q_TITLE DDR5 - CPU0 CHL
J 0
(-9366 26);
DISPLAY 2.446809 (-9366 26);
PAINT GREEN (-9366 26);
FORCEPROP 2 LAST CDS_LIB pure_quanta
J 0
(0 0);
DISPLAY INVISIBLE (0 0);
FORCEPROP 1 LAST CDS_LMAN_SYM_OUTLINE -9475,6775,100,-125
J 0
(0 0);
DISPLAY 0.468085 (0 0);
PAINT GREEN (0 0);
DISPLAY INVISIBLE (0 0);
FORCEPROP 2 LAST PAGE_BORDER TRUE
J 0
(-7890 5250);
DISPLAY 0.638298 (-7890 5250);
PAINT PINK (-7890 5250);
DISPLAY INVISIBLE (-7890 5250);
FORCEPROP 2 LAST CDS_XR_PAGE_TITLE CR-97 : @T6G_MB_LIB.T6G(SCH_1):PAGE97
J 0
(-7890 5250);
DISPLAY 0.638298 (-7890 5250);
PAINT PINK (-7890 5250);
DISPLAY INVISIBLE (-7890 5250);
FORCEPROP 1 LAST Q_DEPT BU9
J 1
(-3763 49);
DISPLAY 1.957447 (-3763 49);
PAINT GREEN (-3763 49);
DISPLAY INVISIBLE (-3763 49);
FORCEPROP 1 LAST COMMENT_BODY TRUE
J 0
(12 -13);
DISPLAY 0.978723 (12 -13);
PAINT GREEN (12 -13);
DISPLAY INVISIBLE (12 -13);
FORCEADD DNS..2
(-8325 1975);
PAINT RED (-8325 1975);
FORCEPROP 2 LAST CDS_LIB mstr_misc
J 0
(-8325 1975);
DISPLAY INVISIBLE (-8325 1975);
FORCEPROP 1 LAST COMMENT_BODY TRUE
R 1
J 0
(-8250 1750);
DISPLAY 0.872340 (-8250 1750);
PAINT PEACH (-8250 1750);
DISPLAY INVISIBLE (-8250 1750);
WIRE 17 -1 (-7775 3700)(-7775 3725);
WIRE 17 -1 (-7775 3700)(-7775 3650);
WIRE 17 -1 (-7775 3725)(-8275 3725);
FORCEPROP 2 LAST SIG_NAME M_L_CPU0_SA_CB<7:0>
J 0
(-8225 3735);
DISPLAY 0.489362 (-8225 3735);
WIRE 17 -1 (-7775 3600)(-7775 3550);
WIRE 17 -1 (-7775 3600)(-7775 3650);
WIRE 17 -1 (-7775 3500)(-7775 3550);
WIRE 17 -1 (-7775 3450)(-7775 3500);
WIRE 17 -1 (-7775 3400)(-7775 3450);
WIRE 17 -1 (-7775 3350)(-7775 3400);
WIRE 17 -1 (-7775 3250)(-7775 3275);
WIRE 17 -1 (-7775 3250)(-7775 3200);
WIRE 17 -1 (-7775 3275)(-8275 3275);
FORCEPROP 2 LAST SIG_NAME M_L_CPU0_SB_CB<7:0>
J 0
(-8225 3285);
DISPLAY 0.489362 (-8225 3285);
WIRE 17 -1 (-7775 4800)(-7775 4850);
WIRE 17 -1 (-7775 4850)(-7775 4900);
WIRE 17 -1 (-7775 4900)(-7775 4950);
WIRE 17 -1 (-7775 4950)(-7775 5000);
WIRE 17 -1 (-7775 5000)(-7775 5050);
WIRE 17 -1 (-7775 5050)(-7775 5100);
WIRE 17 -1 (-7775 5100)(-7775 5125);
WIRE 17 -1 (-7775 5125)(-8275 5125);
FORCEPROP 2 LAST SIG_NAME M_L_CPU0_SA_CA<6:0>
J 0
(-8260 5135);
DISPLAY 0.489362 (-8260 5135);
WIRE 17 -1 (-7775 4400)(-7775 4450);
WIRE 17 -1 (-7775 4450)(-7775 4500);
WIRE 17 -1 (-7775 4500)(-7775 4550);
WIRE 17 -1 (-7775 4550)(-7775 4600);
WIRE 17 -1 (-7775 4600)(-7775 4650);
WIRE 17 -1 (-7775 4650)(-7775 4700);
WIRE 17 -1 (-7775 4700)(-7775 4725);
WIRE 17 -1 (-7775 4725)(-8275 4725);
FORCEPROP 2 LAST SIG_NAME M_L_CPU0_SB_CA<6:0>
J 0
(-8260 4735);
DISPLAY 0.489362 (-8260 4735);
WIRE 17 -1 (-7775 3150)(-7775 3200);
WIRE 17 -1 (-7775 3150)(-7775 3100);
WIRE 17 -1 (-7775 3050)(-7775 3100);
WIRE 17 -1 (-7775 3000)(-7775 3050);
WIRE 17 -1 (-7775 2950)(-7775 3000);
WIRE 17 -1 (-7775 2900)(-7775 2950);
WIRE 17 -1 (-5975 5050)(-5975 5000);
WIRE 17 -1 (-5975 5100)(-5975 5050);
WIRE 17 -1 (-5975 5000)(-5975 4950);
WIRE 17 -1 (-5975 4950)(-5975 4900);
WIRE 17 -1 (-5975 5100)(-5400 5100);
FORCEPROP 2 LAST SIG_NAME M_L_CPU0_SA_DQ<31:0>
J 0
(-5910 5110);
DISPLAY 0.489362 (-5910 5110);
WIRE 17 -1 (-5975 4900)(-5975 4850);
WIRE 17 -1 (-5975 4850)(-5975 4800);
WIRE 17 -1 (-5975 4800)(-5975 4750);
WIRE 17 -1 (-5975 4750)(-5975 4700);
WIRE 17 -1 (-5975 4700)(-5975 4650);
WIRE 17 -1 (-5975 4650)(-5975 4600);
WIRE 17 -1 (-5975 4600)(-5975 4550);
WIRE 17 -1 (-5975 4550)(-5975 4500);
WIRE 17 -1 (-5975 4500)(-5975 4450);
WIRE 17 -1 (-5975 4450)(-5975 4400);
WIRE 17 -1 (-5975 4400)(-5975 4350);
WIRE 17 -1 (-5975 4300)(-5975 4350);
WIRE 17 -1 (-5975 4250)(-5975 4300);
WIRE 17 -1 (-5975 4200)(-5975 4250);
WIRE 17 -1 (-5975 4150)(-5975 4200);
WIRE 17 -1 (-5975 4150)(-5975 4100);
WIRE 17 -1 (-5975 4100)(-5975 4050);
WIRE 17 -1 (-5975 4050)(-5975 4000);
WIRE 17 -1 (-5975 4000)(-5975 3950);
WIRE 17 -1 (-5975 3950)(-5975 3900);
WIRE 17 -1 (-5975 3900)(-5975 3850);
WIRE 17 -1 (-5975 3850)(-5975 3800);
WIRE 17 -1 (-5975 3800)(-5975 3750);
WIRE 17 -1 (-5975 3700)(-5975 3750);
WIRE 17 -1 (-5975 3650)(-5975 3700);
WIRE 17 -1 (-5975 3600)(-5975 3650);
WIRE 17 -1 (-5975 3550)(-5975 3600);
WIRE 17 -1 (-5975 3450)(-5400 3450);
FORCEPROP 2 LAST SIG_NAME M_L_CPU0_SB_DQ<31:0>
J 0
(-5910 3460);
DISPLAY 0.489362 (-5910 3460);
WIRE 17 -1 (-5975 3450)(-5975 3400);
WIRE 17 -1 (-5975 3400)(-5975 3350);
WIRE 17 -1 (-5975 3350)(-5975 3300);
WIRE 17 -1 (-5975 3300)(-5975 3250);
WIRE 17 -1 (-5975 3250)(-5975 3200);
WIRE 17 -1 (-5975 3200)(-5975 3150);
WIRE 17 -1 (-5975 3150)(-5975 3100);
WIRE 17 -1 (-5975 3100)(-5975 3050);
WIRE 17 -1 (-5975 3050)(-5975 3000);
WIRE 17 -1 (-5975 3000)(-5975 2950);
WIRE 17 -1 (-5975 2950)(-5975 2900);
WIRE 17 -1 (-5975 2900)(-5975 2850);
WIRE 17 -1 (-5975 2850)(-5975 2800);
WIRE 17 -1 (-5975 2800)(-5975 2750);
WIRE 17 -1 (-5975 2750)(-5975 2700);
WIRE 17 -1 (-5975 2650)(-5975 2700);
WIRE 17 -1 (-5975 2600)(-5975 2650);
WIRE 17 -1 (-5975 2550)(-5975 2600);
WIRE 17 -1 (-5975 2500)(-5975 2550);
WIRE 17 -1 (-5975 2500)(-5975 2450);
WIRE 17 -1 (-5975 2450)(-5975 2400);
WIRE 17 -1 (-5975 2400)(-5975 2350);
WIRE 17 -1 (-5975 2350)(-5975 2300);
WIRE 17 -1 (-5975 2300)(-5975 2250);
WIRE 17 -1 (-5975 2250)(-5975 2200);
WIRE 17 -1 (-5975 2200)(-5975 2150);
WIRE 17 -1 (-5975 2150)(-5975 2100);
WIRE 17 -1 (-5975 2050)(-5975 2100);
WIRE 17 -1 (-5975 2000)(-5975 2050);
WIRE 17 -1 (-5975 1950)(-5975 2000);
WIRE 17 -1 (-5975 1900)(-5975 1950);
WIRE 17 -1 (-3250 4175)(-3250 4075);
WIRE 17 -1 (-3250 4275)(-3250 4175);
WIRE 17 -1 (-3250 4075)(-3250 3975);
WIRE 17 -1 (-3250 3975)(-3250 3875);
WIRE 17 -1 (-3250 4300)(-3250 4275);
WIRE 17 -1 (-3250 4300)(-2550 4300);
FORCEPROP 2 LAST SIG_NAME M_L_CPU0_SA_DQS_DN<9:0>
J 0
(-3185 4310);
DISPLAY 0.489362 (-3185 4310);
WIRE 17 -1 (-3450 4125)(-3450 4025);
WIRE 17 -1 (-3450 4225)(-3450 4125);
WIRE 17 -1 (-3450 4025)(-3450 3925);
WIRE 17 -1 (-3450 3825)(-3450 3925);
WIRE 17 -1 (-3450 4325)(-3450 4225);
WIRE 17 -1 (-3450 4350)(-3450 4325);
WIRE 17 -1 (-3450 3725)(-3450 3825);
WIRE 17 -1 (-3450 3625)(-3450 3725);
WIRE 17 -1 (-3450 4350)(-2550 4350);
FORCEPROP 2 LAST SIG_NAME M_L_CPU0_SA_DQS_DP<9:0>
J 0
(-3185 4360);
DISPLAY 0.489362 (-3185 4360);
WIRE 17 -1 (-3450 3275)(-3450 3175);
WIRE 17 -1 (-3450 3300)(-3450 3275);
WIRE 17 -1 (-3450 3175)(-3450 3075);
WIRE 17 -1 (-3450 3075)(-3450 2975);
WIRE 17 -1 (-3450 3300)(-2550 3300);
FORCEPROP 2 LAST SIG_NAME M_L_CPU0_SB_DQS_DP<9:0>
J 0
(-3185 3310);
DISPLAY 0.489362 (-3185 3310);
WIRE 17 -1 (-3250 3225)(-3250 3125);
WIRE 17 -1 (-3250 3250)(-3250 3225);
WIRE 17 -1 (-3250 3125)(-3250 3025);
WIRE 17 -1 (-3250 3025)(-3250 2925);
WIRE 17 -1 (-3250 3250)(-2550 3250);
FORCEPROP 2 LAST SIG_NAME M_L_CPU0_SB_DQS_DN<9:0>
J 0
(-3185 3260);
DISPLAY 0.489362 (-3185 3260);
WIRE 17 -1 (-3450 2975)(-3450 2875);
WIRE 17 -1 (-3250 3475)(-3250 3375);
WIRE 17 -1 (-3250 3575)(-3250 3475);
WIRE 17 -1 (-3250 3575)(-3250 3675);
WIRE 17 -1 (-3250 3675)(-3250 3775);
WIRE 17 -1 (-3250 3775)(-3250 3875);
WIRE 17 -1 (-3450 3525)(-3450 3425);
WIRE 17 -1 (-3450 3625)(-3450 3525);
WIRE 17 -1 (-3250 2425)(-3250 2325);
WIRE 17 -1 (-3250 2525)(-3250 2425);
WIRE 17 -1 (-3250 2525)(-3250 2625);
WIRE 17 -1 (-3250 2625)(-3250 2725);
WIRE 17 -1 (-3250 2725)(-3250 2825);
WIRE 17 -1 (-3250 2925)(-3250 2825);
WIRE 17 -1 (-3450 2475)(-3450 2375);
WIRE 17 -1 (-3450 2575)(-3450 2475);
WIRE 17 -1 (-3450 2575)(-3450 2675);
WIRE 17 -1 (-3450 2675)(-3450 2775);
WIRE 17 -1 (-3450 2775)(-3450 2875);
WIRE 16 -1 (-6450 750)(-6450 825);
WIRE 16 -1 (-8600 2725)(-8600 2800);
WIRE 16 -1 (-8350 2075)(-8350 2100);
WIRE 16 -1 (-7475 2725)(-8100 2725);
FORCEPROP 2 LAST SIG_NAME M_L_CPU0_ALERT_N
J 0
(-8085 2735);
DISPLAY 0.489362 (-8085 2735);
WIRE 16 -1 (-7475 2775)(-8100 2775);
FORCEPROP 2 LAST SIG_NAME M_L_CPU0_RESET_N
J 0
(-8085 2785);
DISPLAY 0.489362 (-8085 2785);
WIRE 16 -1 (-8950 1825)(-8575 1825);
FORCEPROP 2 LAST SIG_NAME PWRGD_CHGL_CPU0
J 0
(-8935 1835);
DISPLAY 0.489362 (-8935 1835);
WIRE 16 -1 (-6075 2725)(-6275 2725);
WIRE 16 -1 (-6275 2225)(-6075 2225);
WIRE 16 -1 (-6075 2325)(-6275 2325);
WIRE 16 -1 (-6275 2425)(-6075 2425);
WIRE 16 -1 (-7475 3075)(-7675 3075);
WIRE 16 -1 (-6075 3625)(-6275 3625);
WIRE 16 -1 (-6275 3675)(-6075 3675);
WIRE 16 -1 (-6075 3725)(-6275 3725);
WIRE 16 -1 (-7475 1625)(-8275 1625);
FORCEPROP 2 LAST SIG_NAME M_L_CPU0_SB_RSP<0>
J 0
(-8225 1635);
DISPLAY 0.489362 (-8225 1635);
WIRE 16 -1 (-3700 3250)(-3550 3250);
WIRE 16 -1 (-3700 3200)(-3350 3200);
WIRE 16 -1 (-3700 4300)(-3550 4300);
WIRE 16 -1 (-3700 4250)(-3350 4250);
WIRE 16 -1 (-3550 4200)(-3700 4200);
WIRE 16 -1 (-3700 4150)(-3350 4150);
WIRE 16 -1 (-3700 3000)(-3350 3000);
WIRE 16 -1 (-3550 4100)(-3700 4100);
WIRE 16 -1 (-3550 2950)(-3700 2950);
WIRE 16 -1 (-3700 2900)(-3350 2900);
WIRE 16 -1 (-3700 3950)(-3350 3950);
WIRE 16 -1 (-3700 2850)(-3550 2850);
WIRE 16 -1 (-3700 2800)(-3350 2800);
WIRE 16 -1 (-3700 3900)(-3550 3900);
WIRE 16 -1 (-3700 3850)(-3350 3850);
WIRE 16 -1 (-3550 2750)(-3700 2750);
WIRE 16 -1 (-3700 2700)(-3350 2700);
WIRE 16 -1 (-3550 3800)(-3700 3800);
WIRE 16 -1 (-3700 3750)(-3350 3750);
WIRE 16 -1 (-3550 2650)(-3700 2650);
WIRE 16 -1 (-3700 2600)(-3350 2600);
WIRE 16 -1 (-3550 3700)(-3700 3700);
WIRE 16 -1 (-3700 3650)(-3350 3650);
WIRE 16 -1 (-3550 2550)(-3700 2550);
WIRE 16 -1 (-3700 2500)(-3350 2500);
WIRE 16 -1 (-3550 3600)(-3700 3600);
WIRE 16 -1 (-3700 3550)(-3350 3550);
WIRE 16 -1 (-3700 2450)(-3550 2450);
WIRE 16 -1 (-3700 2400)(-3350 2400);
WIRE 16 -1 (-3700 3500)(-3550 3500);
WIRE 16 -1 (-3700 3450)(-3350 3450);
WIRE 16 -1 (-3550 2350)(-3700 2350);
WIRE 16 -1 (-3700 2300)(-3350 2300);
WIRE 16 -1 (-3550 3400)(-3700 3400);
WIRE 16 -1 (-3700 3350)(-3350 3350);
WIRE 16 -1 (-3550 3050)(-3700 3050);
WIRE 16 -1 (-3700 3100)(-3350 3100);
WIRE 16 -1 (-3550 3150)(-3700 3150);
WIRE 16 -1 (-3550 4000)(-3700 4000);
WIRE 16 -1 (-3700 4050)(-3350 4050);
WIRE 16 -1 (-6075 4425)(-6275 4425);
WIRE 16 -1 (-6075 5025)(-6275 5025);
WIRE 16 -1 (-6275 5075)(-6075 5075);
WIRE 16 -1 (-7475 4225)(-8275 4225);
FORCEPROP 2 LAST SIG_NAME M_L_CPU0_SB_PAR
J 0
(-8225 4235);
DISPLAY 0.489362 (-8225 4235);
WIRE 16 -1 (-7475 4275)(-8275 4275);
FORCEPROP 2 LAST SIG_NAME M_L_CPU0_SA_PAR
J 0
(-8225 4285);
DISPLAY 0.489362 (-8225 4285);
WIRE 16 -1 (-6075 1875)(-6275 1875);
WIRE 16 -1 (-6075 1925)(-6275 1925);
WIRE 16 -1 (-6075 1975)(-6275 1975);
WIRE 16 -1 (-6275 2025)(-6075 2025);
WIRE 16 -1 (-6075 2075)(-6275 2075);
WIRE 16 -1 (-6075 2125)(-6275 2125);
WIRE 16 -1 (-6075 2175)(-6275 2175);
WIRE 16 -1 (-6075 2275)(-6275 2275);
WIRE 16 -1 (-6075 2375)(-6275 2375);
WIRE 16 -1 (-6075 2475)(-6275 2475);
WIRE 16 -1 (-6075 2525)(-6275 2525);
WIRE 16 -1 (-6075 2575)(-6275 2575);
WIRE 16 -1 (-6275 2625)(-6075 2625);
WIRE 16 -1 (-6075 2675)(-6275 2675);
WIRE 16 -1 (-6075 2775)(-6275 2775);
WIRE 16 -1 (-6275 2825)(-6075 2825);
WIRE 16 -1 (-6075 2875)(-6275 2875);
WIRE 16 -1 (-6075 2925)(-6275 2925);
WIRE 16 -1 (-6075 2975)(-6275 2975);
WIRE 16 -1 (-6275 3025)(-6075 3025);
WIRE 16 -1 (-6075 3075)(-6275 3075);
WIRE 16 -1 (-6075 3125)(-6275 3125);
WIRE 16 -1 (-6075 3175)(-6275 3175);
WIRE 16 -1 (-6275 3225)(-6075 3225);
WIRE 16 -1 (-6075 3275)(-6275 3275);
WIRE 16 -1 (-6075 3325)(-6275 3325);
WIRE 16 -1 (-6075 3375)(-6275 3375);
WIRE 16 -1 (-6275 3425)(-6075 3425);
WIRE 16 -1 (-6075 3525)(-6275 3525);
WIRE 16 -1 (-6075 3575)(-6275 3575);
WIRE 16 -1 (-6075 3775)(-6275 3775);
WIRE 16 -1 (-6075 3825)(-6275 3825);
WIRE 16 -1 (-6275 3875)(-6075 3875);
WIRE 16 -1 (-6075 3925)(-6275 3925);
WIRE 16 -1 (-6075 3975)(-6275 3975);
WIRE 16 -1 (-6075 4025)(-6275 4025);
WIRE 16 -1 (-6275 4075)(-6075 4075);
WIRE 16 -1 (-6075 4125)(-6275 4125);
WIRE 16 -1 (-6075 4175)(-6275 4175);
WIRE 16 -1 (-6075 4225)(-6275 4225);
WIRE 16 -1 (-6275 4275)(-6075 4275);
WIRE 16 -1 (-6075 4325)(-6275 4325);
WIRE 16 -1 (-6075 4375)(-6275 4375);
WIRE 16 -1 (-6275 4475)(-6075 4475);
WIRE 16 -1 (-6075 4525)(-6275 4525);
WIRE 16 -1 (-6075 4575)(-6275 4575);
WIRE 16 -1 (-6075 4625)(-6275 4625);
WIRE 16 -1 (-6275 4675)(-6075 4675);
WIRE 16 -1 (-6075 4725)(-6275 4725);
WIRE 16 -1 (-6075 4775)(-6275 4775);
WIRE 16 -1 (-6075 4825)(-6275 4825);
WIRE 16 -1 (-6275 4875)(-6075 4875);
WIRE 16 -1 (-6075 4925)(-6275 4925);
WIRE 16 -1 (-6075 4975)(-6275 4975);
WIRE 16 -1 (-7475 3975)(-8275 3975);
FORCEPROP 2 LAST SIG_NAME M_L_CPU0_SB_CS_N<1>
J 0
(-8225 3985);
DISPLAY 0.489362 (-8225 3985);
WIRE 16 -1 (-7475 4125)(-8275 4125);
FORCEPROP 2 LAST SIG_NAME M_L_CPU0_SA_CS_N<1>
J 0
(-8225 4135);
DISPLAY 0.489362 (-8225 4135);
WIRE 16 -1 (-7475 3925)(-8275 3925);
FORCEPROP 2 LAST SIG_NAME M_L_CPU0_SB_CS_N<0>
J 0
(-8225 3935);
DISPLAY 0.489362 (-8225 3935);
WIRE 16 -1 (-7475 4075)(-8275 4075);
FORCEPROP 2 LAST SIG_NAME M_L_CPU0_SA_CS_N<0>
J 0
(-8225 4085);
DISPLAY 0.489362 (-8225 4085);
WIRE 16 -1 (-7475 3825)(-8275 3825);
FORCEPROP 2 LAST SIG_NAME M_L_CPU0_CLK_DP<0>
J 0
(-8225 3835);
DISPLAY 0.489362 (-8225 3835);
WIRE 16 -1 (-7475 3775)(-8275 3775);
FORCEPROP 2 LAST SIG_NAME M_L_CPU0_CLK_DN<0>
J 0
(-8225 3785);
DISPLAY 0.489362 (-8225 3785);
WIRE 16 -1 (-7475 2875)(-7675 2875);
WIRE 16 -1 (-7475 2925)(-7675 2925);
WIRE 16 -1 (-7475 2975)(-7675 2975);
WIRE 16 -1 (-7475 3025)(-7675 3025);
WIRE 16 -1 (-7475 3125)(-7675 3125);
WIRE 16 -1 (-7475 3175)(-7675 3175);
WIRE 16 -1 (-7475 3325)(-7675 3325);
WIRE 16 -1 (-7475 3425)(-7675 3425);
WIRE 16 -1 (-7475 3475)(-7675 3475);
WIRE 16 -1 (-7475 3575)(-7675 3575);
WIRE 16 -1 (-7475 3625)(-7675 3625);
WIRE 16 -1 (-7475 4675)(-7675 4675);
WIRE 16 -1 (-7475 5075)(-7675 5075);
WIRE 16 -1 (-7475 4625)(-7675 4625);
WIRE 16 -1 (-7475 5025)(-7675 5025);
WIRE 16 -1 (-7475 4575)(-7675 4575);
WIRE 16 -1 (-7475 4975)(-7675 4975);
WIRE 16 -1 (-7475 4525)(-7675 4525);
WIRE 16 -1 (-7475 4925)(-7675 4925);
WIRE 16 -1 (-7475 4475)(-7675 4475);
WIRE 16 -1 (-7475 4875)(-7675 4875);
WIRE 16 -1 (-7475 4425)(-7675 4425);
WIRE 16 -1 (-7475 4825)(-7675 4825);
WIRE 16 -1 (-7475 4375)(-7675 4375);
WIRE 16 -1 (-7475 4775)(-7675 4775);
WIRE 16 -1 (-7475 3225)(-7675 3225);
WIRE 16 -1 (-7475 3375)(-7675 3375);
WIRE 16 -1 (-7475 3525)(-7675 3525);
WIRE 16 -1 (-7475 3675)(-7675 3675);
WIRE 16 -1 (-6450 1100)(-6450 1025);
WIRE 16 -1 (-6450 1100)(-7175 1100);
FORCEPROP 2 LAST SIG_NAME PD_CHL_CPU0_DIMM_SAA
J 0
(-7160 1110);
DISPLAY 0.489362 (-7160 1110);
WIRE 16 -1 (-7475 1675)(-8275 1675);
FORCEPROP 2 LAST SIG_NAME M_L_CPU0_SA_RSP<0>
J 0
(-8225 1685);
DISPLAY 0.489362 (-8225 1685);
WIRE 16 -1 (-8150 1825)(-8150 2225);
WIRE 16 -1 (-8150 1825)(-8350 1825);
WIRE 16 -1 (-7475 2225)(-8150 2225);
FORCEPROP 2 LAST SIG_NAME PWRGD_CHL_CPU0_DIMM
J 0
(-8000 2235);
DISPLAY 0.489362 (-8000 2235);
FORCEPROP 2 LASTPROP $XRERR UNIQUE?
J 0
(-8240 2235);
DISPLAY 0.638298 (-8240 2235);
PAINT MONO (-8240 2235);
DISPLAY INVISIBLE (-8240 2235);
WIRE 16 -1 (-8350 1875)(-8350 1825);
WIRE 16 -1 (-8350 1825)(-8375 1825);
WIRE 16 -1 (-7875 2300)(-8375 2300);
FORCEPROP 2 LAST SIG_NAME I3C_SPD_DDRGL_CPU0_SCL
J 0
(-8435 2310);
DISPLAY 0.489362 (-8435 2310);
WIRE 16 -1 (-2200 5075)(-1900 5075);
WIRE 16 -1 (-2200 5125)(-2200 5075);
WIRE 16 -1 (-1900 5125)(-2200 5125);
WIRE 16 -1 (-2200 5125)(-2200 5175);
WIRE 16 -1 (-1900 5175)(-2200 5175);
WIRE 16 -1 (-2200 5175)(-2200 5800);
WIRE 16 -1 (-2325 5800)(-2200 5800);
WIRE 16 -1 (-2325 5800)(-2325 5700);
WIRE 16 -1 (-2325 5800)(-2900 5800);
WIRE 16 -1 (-2900 5700)(-2900 5800);
WIRE 16 -1 (-2900 5800)(-2900 5875);
WIRE 16 -1 (-2325 5375)(-2325 5500);
WIRE 16 -1 (-2325 5375)(-2900 5375);
WIRE 16 -1 (-2900 5375)(-2900 5500);
WIRE 16 -1 (-2900 5375)(-2900 5300);
WIRE 16 -1 (-400 5175)(-400 5125);
WIRE 16 -1 (-400 5175)(-700 5175);
WIRE 16 -1 (-400 5125)(-700 5125);
WIRE 16 -1 (-400 5125)(-400 5075);
WIRE 16 -1 (-400 5075)(-400 5025);
WIRE 16 -1 (-400 5075)(-700 5075);
WIRE 16 -1 (-400 5025)(-400 4975);
WIRE 16 -1 (-400 5025)(-700 5025);
WIRE 16 -1 (-400 4975)(-400 4925);
WIRE 16 -1 (-400 4975)(-700 4975);
WIRE 16 -1 (-400 4925)(-400 4875);
WIRE 16 -1 (-400 4925)(-700 4925);
WIRE 16 -1 (-400 4875)(-400 4825);
WIRE 16 -1 (-400 4875)(-700 4875);
WIRE 16 -1 (-400 4825)(-400 4775);
WIRE 16 -1 (-400 4825)(-700 4825);
WIRE 16 -1 (-400 4775)(-400 4725);
WIRE 16 -1 (-400 4775)(-700 4775);
WIRE 16 -1 (-400 4725)(-400 4675);
WIRE 16 -1 (-400 4725)(-700 4725);
WIRE 16 -1 (-400 4675)(-400 4625);
WIRE 16 -1 (-400 4675)(-700 4675);
WIRE 16 -1 (-400 4625)(-400 4575);
WIRE 16 -1 (-400 4625)(-700 4625);
WIRE 16 -1 (-400 4575)(-400 4525);
WIRE 16 -1 (-400 4575)(-700 4575);
WIRE 16 -1 (-400 4525)(-400 4475);
WIRE 16 -1 (-400 4525)(-700 4525);
WIRE 16 -1 (-400 4475)(-400 4425);
WIRE 16 -1 (-400 4475)(-700 4475);
WIRE 16 -1 (-400 4425)(-400 4375);
WIRE 16 -1 (-400 4425)(-700 4425);
WIRE 16 -1 (-400 4375)(-400 4325);
WIRE 16 -1 (-400 4375)(-700 4375);
WIRE 16 -1 (-400 4325)(-400 4275);
WIRE 16 -1 (-400 4325)(-700 4325);
WIRE 16 -1 (-400 4275)(-400 4225);
WIRE 16 -1 (-400 4275)(-700 4275);
WIRE 16 -1 (-400 4225)(-400 4175);
WIRE 16 -1 (-400 4225)(-700 4225);
WIRE 16 -1 (-400 4175)(-400 4125);
WIRE 16 -1 (-400 4175)(-700 4175);
WIRE 16 -1 (-400 4125)(-700 4125);
WIRE 16 -1 (-400 4125)(-400 4075);
WIRE 16 -1 (-400 4075)(-400 4025);
WIRE 16 -1 (-400 4075)(-700 4075);
WIRE 16 -1 (-400 4025)(-400 3975);
WIRE 16 -1 (-400 4025)(-700 4025);
WIRE 16 -1 (-400 3975)(-400 3925);
WIRE 16 -1 (-400 3975)(-700 3975);
WIRE 16 -1 (-400 3925)(-400 3875);
WIRE 16 -1 (-400 3925)(-700 3925);
WIRE 16 -1 (-400 3875)(-400 3825);
WIRE 16 -1 (-400 3875)(-700 3875);
WIRE 16 -1 (-400 3825)(-400 3775);
WIRE 16 -1 (-400 3825)(-700 3825);
WIRE 16 -1 (-400 3775)(-400 3725);
WIRE 16 -1 (-400 3775)(-700 3775);
WIRE 16 -1 (-400 3725)(-400 3675);
WIRE 16 -1 (-400 3725)(-700 3725);
WIRE 16 -1 (-400 3675)(-400 3625);
WIRE 16 -1 (-400 3675)(-700 3675);
WIRE 16 -1 (-400 3625)(-400 3575);
WIRE 16 -1 (-400 3625)(-700 3625);
WIRE 16 -1 (-400 3575)(-400 3525);
WIRE 16 -1 (-400 3575)(-700 3575);
WIRE 16 -1 (-400 3525)(-400 3475);
WIRE 16 -1 (-400 3525)(-700 3525);
WIRE 16 -1 (-400 3475)(-400 3425);
WIRE 16 -1 (-400 3475)(-700 3475);
WIRE 16 -1 (-400 3425)(-400 3375);
WIRE 16 -1 (-400 3425)(-700 3425);
WIRE 16 -1 (-400 3375)(-400 3325);
WIRE 16 -1 (-400 3375)(-700 3375);
WIRE 16 -1 (-400 3325)(-400 3275);
WIRE 16 -1 (-400 3325)(-700 3325);
WIRE 16 -1 (-400 3275)(-400 3225);
WIRE 16 -1 (-400 3275)(-700 3275);
WIRE 16 -1 (-400 3225)(-400 3175);
WIRE 16 -1 (-400 3225)(-700 3225);
WIRE 16 -1 (-400 3175)(-400 3125);
WIRE 16 -1 (-400 3175)(-700 3175);
WIRE 16 -1 (-400 3125)(-400 3075);
WIRE 16 -1 (-400 3125)(-700 3125);
WIRE 16 -1 (-400 3075)(-700 3075);
WIRE 16 -1 (-400 3075)(-400 3025);
WIRE 16 -1 (-400 3025)(-400 2975);
WIRE 16 -1 (-400 3025)(-700 3025);
WIRE 16 -1 (-400 2975)(-400 2925);
WIRE 16 -1 (-400 2975)(-700 2975);
WIRE 16 -1 (-400 2925)(-400 2875);
WIRE 16 -1 (-400 2925)(-700 2925);
WIRE 16 -1 (-400 2875)(-400 2825);
WIRE 16 -1 (-400 2875)(-700 2875);
WIRE 16 -1 (-400 2825)(-400 2775);
WIRE 16 -1 (-400 2825)(-700 2825);
WIRE 16 -1 (-400 2775)(-400 2725);
WIRE 16 -1 (-400 2775)(-700 2775);
WIRE 16 -1 (-400 2725)(-400 2675);
WIRE 16 -1 (-400 2725)(-700 2725);
WIRE 16 -1 (-400 2675)(-400 2625);
WIRE 16 -1 (-400 2675)(-700 2675);
WIRE 16 -1 (-400 2625)(-400 2575);
WIRE 16 -1 (-400 2625)(-700 2625);
WIRE 16 -1 (-400 2575)(-400 2525);
WIRE 16 -1 (-400 2575)(-700 2575);
WIRE 16 -1 (-400 2525)(-400 2475);
WIRE 16 -1 (-400 2525)(-700 2525);
WIRE 16 -1 (-400 2475)(-400 2425);
WIRE 16 -1 (-400 2475)(-700 2475);
WIRE 16 -1 (-400 2425)(-400 2375);
WIRE 16 -1 (-400 2425)(-700 2425);
WIRE 16 -1 (-400 2375)(-400 2325);
WIRE 16 -1 (-400 2375)(-700 2375);
WIRE 16 -1 (-400 2325)(-400 2275);
WIRE 16 -1 (-400 2325)(-700 2325);
WIRE 16 -1 (-400 2275)(-400 2225);
WIRE 16 -1 (-400 2275)(-700 2275);
WIRE 16 -1 (-400 2225)(-400 2175);
WIRE 16 -1 (-400 2225)(-700 2225);
WIRE 16 -1 (-400 2175)(-400 2125);
WIRE 16 -1 (-400 2175)(-700 2175);
WIRE 16 -1 (-400 2125)(-400 2075);
WIRE 16 -1 (-400 2125)(-700 2125);
WIRE 16 -1 (-400 2075)(-700 2075);
WIRE 16 -1 (-400 2075)(-400 2025);
WIRE 16 -1 (-400 2025)(-400 1925);
WIRE 16 -1 (-400 2025)(-700 2025);
WIRE 16 -1 (-400 1925)(-400 1875);
WIRE 16 -1 (-400 1925)(-700 1925);
WIRE 16 -1 (-400 1875)(-400 1825);
WIRE 16 -1 (-400 1875)(-700 1875);
WIRE 16 -1 (-400 1825)(-400 1575);
WIRE 16 -1 (-400 1825)(-700 1825);
WIRE 16 -1 (-1900 5025)(-2200 5025);
WIRE 16 -1 (-2200 5025)(-2200 4975);
WIRE 16 -1 (-1900 4975)(-2200 4975);
WIRE 16 -1 (-2200 4975)(-2200 4925);
WIRE 16 -1 (-1900 4925)(-2200 4925);
WIRE 16 -1 (-2200 4925)(-2200 4875);
WIRE 16 -1 (-1900 4875)(-2200 4875);
WIRE 16 -1 (-2200 4875)(-2200 4825);
WIRE 16 -1 (-1900 4825)(-2200 4825);
WIRE 16 -1 (-2200 4825)(-2200 4775);
WIRE 16 -1 (-1900 4775)(-2200 4775);
WIRE 16 -1 (-2200 4775)(-2200 4725);
WIRE 16 -1 (-1900 4725)(-2200 4725);
WIRE 16 -1 (-2200 4725)(-2200 4675);
WIRE 16 -1 (-1900 4675)(-2200 4675);
WIRE 16 -1 (-2200 4675)(-2200 4625);
WIRE 16 -1 (-1900 4625)(-2200 4625);
WIRE 16 -1 (-2200 4625)(-2200 4575);
WIRE 16 -1 (-1900 4575)(-2200 4575);
WIRE 16 -1 (-2200 4575)(-2200 4525);
WIRE 16 -1 (-1900 4525)(-2200 4525);
WIRE 16 -1 (-2200 4525)(-2200 4475);
WIRE 16 -1 (-1900 4475)(-2200 4475);
WIRE 16 -1 (-2200 4475)(-2200 4425);
WIRE 16 -1 (-1900 4425)(-2200 4425);
WIRE 16 -1 (-2200 4425)(-2200 4375);
WIRE 16 -1 (-1900 4375)(-2200 4375);
WIRE 16 -1 (-2200 4375)(-2200 4325);
WIRE 16 -1 (-1900 4325)(-2200 4325);
WIRE 16 -1 (-2200 4325)(-2200 4275);
WIRE 16 -1 (-1900 4275)(-2200 4275);
WIRE 16 -1 (-2200 4275)(-2200 4225);
WIRE 16 -1 (-1900 4225)(-2200 4225);
WIRE 16 -1 (-2200 4225)(-2200 4175);
WIRE 16 -1 (-1900 4175)(-2200 4175);
WIRE 16 -1 (-2200 4175)(-2200 4125);
WIRE 16 -1 (-1900 4125)(-2200 4125);
WIRE 16 -1 (-2200 4125)(-2200 4075);
WIRE 16 -1 (-1900 4075)(-2200 4075);
WIRE 16 -1 (-2200 4075)(-2200 4025);
WIRE 16 -1 (-1900 4025)(-2200 4025);
WIRE 16 -1 (-2200 4025)(-2200 3975);
WIRE 16 -1 (-1900 3975)(-2200 3975);
WIRE 16 -1 (-2200 3975)(-2200 3925);
WIRE 16 -1 (-1900 3925)(-2200 3925);
WIRE 16 -1 (-2200 3925)(-2200 3875);
WIRE 16 -1 (-1900 3875)(-2200 3875);
WIRE 16 -1 (-2200 3875)(-2200 3825);
WIRE 16 -1 (-1900 3825)(-2200 3825);
WIRE 16 -1 (-2200 3825)(-2200 3775);
WIRE 16 -1 (-1900 3775)(-2200 3775);
WIRE 16 -1 (-2200 3775)(-2200 3725);
WIRE 16 -1 (-1900 3725)(-2200 3725);
WIRE 16 -1 (-2200 3725)(-2200 3675);
WIRE 16 -1 (-1900 3675)(-2200 3675);
WIRE 16 -1 (-2200 3675)(-2200 3625);
WIRE 16 -1 (-1900 3625)(-2200 3625);
WIRE 16 -1 (-2200 3625)(-2200 3575);
WIRE 16 -1 (-1900 3575)(-2200 3575);
WIRE 16 -1 (-2200 3575)(-2200 3525);
WIRE 16 -1 (-1900 3525)(-2200 3525);
WIRE 16 -1 (-2200 3525)(-2200 3475);
WIRE 16 -1 (-1900 3475)(-2200 3475);
WIRE 16 -1 (-2200 3475)(-2200 3425);
WIRE 16 -1 (-1900 3425)(-2200 3425);
WIRE 16 -1 (-2200 3425)(-2200 3375);
WIRE 16 -1 (-1900 3375)(-2200 3375);
WIRE 16 -1 (-2200 3375)(-2200 3325);
WIRE 16 -1 (-1900 3325)(-2200 3325);
WIRE 16 -1 (-2200 3325)(-2200 3275);
WIRE 16 -1 (-1900 3275)(-2200 3275);
WIRE 16 -1 (-2200 3275)(-2200 3225);
WIRE 16 -1 (-1900 3225)(-2200 3225);
WIRE 16 -1 (-2200 3225)(-2200 3175);
WIRE 16 -1 (-1900 3175)(-2200 3175);
WIRE 16 -1 (-2200 3175)(-2200 3125);
WIRE 16 -1 (-1900 3125)(-2200 3125);
WIRE 16 -1 (-2200 3125)(-2200 3075);
WIRE 16 -1 (-1900 3075)(-2200 3075);
WIRE 16 -1 (-2200 3075)(-2200 3025);
WIRE 16 -1 (-1900 3025)(-2200 3025);
WIRE 16 -1 (-2200 3025)(-2200 2975);
WIRE 16 -1 (-1900 2975)(-2200 2975);
WIRE 16 -1 (-2200 2975)(-2200 2925);
WIRE 16 -1 (-1900 2925)(-2200 2925);
WIRE 16 -1 (-2200 2925)(-2200 2875);
WIRE 16 -1 (-1900 2875)(-2200 2875);
WIRE 16 -1 (-2200 2875)(-2200 2825);
WIRE 16 -1 (-1900 2825)(-2200 2825);
WIRE 16 -1 (-2200 2825)(-2200 2775);
WIRE 16 -1 (-1900 2775)(-2200 2775);
WIRE 16 -1 (-2200 2775)(-2200 2725);
WIRE 16 -1 (-1900 2725)(-2200 2725);
WIRE 16 -1 (-2200 2725)(-2200 2675);
WIRE 16 -1 (-1900 2675)(-2200 2675);
WIRE 16 -1 (-2200 2675)(-2200 2625);
WIRE 16 -1 (-1900 2625)(-2200 2625);
WIRE 16 -1 (-2200 2625)(-2200 2575);
WIRE 16 -1 (-1900 2575)(-2200 2575);
WIRE 16 -1 (-2200 2575)(-2200 2525);
WIRE 16 -1 (-1900 2525)(-2200 2525);
WIRE 16 -1 (-2200 2525)(-2200 2475);
WIRE 16 -1 (-1900 2475)(-2200 2475);
WIRE 16 -1 (-2200 2475)(-2200 2425);
WIRE 16 -1 (-1900 2425)(-2200 2425);
WIRE 16 -1 (-2200 2425)(-2200 2375);
WIRE 16 -1 (-1900 2375)(-2200 2375);
WIRE 16 -1 (-2200 2375)(-2200 2325);
WIRE 16 -1 (-1900 2325)(-2200 2325);
WIRE 16 -1 (-2200 2325)(-2200 2275);
WIRE 16 -1 (-1900 2275)(-2200 2275);
WIRE 16 -1 (-2200 2275)(-2200 2225);
WIRE 16 -1 (-1900 2225)(-2200 2225);
WIRE 16 -1 (-2200 2225)(-2200 2175);
WIRE 16 -1 (-1900 2175)(-2200 2175);
WIRE 16 -1 (-2200 2175)(-2200 2125);
WIRE 16 -1 (-1900 2125)(-2200 2125);
WIRE 16 -1 (-2200 2125)(-2200 2075);
WIRE 16 -1 (-1900 2075)(-2200 2075);
WIRE 16 -1 (-2200 2075)(-2200 2025);
WIRE 16 -1 (-1900 2025)(-2200 2025);
WIRE 16 -1 (-2200 2025)(-2200 1975);
WIRE 16 -1 (-1900 1975)(-2200 1975);
WIRE 16 -1 (-2200 1975)(-2200 1925);
WIRE 16 -1 (-1900 1925)(-2200 1925);
WIRE 16 -1 (-2200 1925)(-2200 1800);
WIRE 16 -1 (-8600 3000)(-8600 3025);
WIRE 16 -1 (-8600 3025)(-8500 3025);
WIRE 16 -1 (-8500 3050)(-8500 3025);
WIRE 16 -1 (-8500 3025)(-8500 2625);
WIRE 16 -1 (-8500 2625)(-7475 2625);
WIRE 16 -1 (-7475 2475)(-7575 2475);
FORCEPROP 2 LAST SIG_NAME I3C_SPD_DDRL_CPU0_SCL
J 0
(-7960 2485);
DISPLAY 0.446809 (-7960 2485);
FORCEPROP 2 LASTPROP $XRERR UNIQUE?
J 0
(-8200 2485);
DISPLAY 0.638298 (-8200 2485);
PAINT MONO (-8200 2485);
DISPLAY INVISIBLE (-8200 2485);
WIRE 16 -1 (-7575 2475)(-7575 2300);
WIRE 16 -1 (-7575 2300)(-7675 2300);
WIRE 16 -1 (-7475 2525)(-8025 2525);
FORCEPROP 2 LAST SIG_NAME I3C_SPD_DDRL_CPU0_SDA
J 0
(-7960 2535);
DISPLAY 0.446809 (-7960 2535);
FORCEPROP 2 LASTPROP $XRERR UNIQUE?
J 0
(-8200 2535);
DISPLAY 0.638298 (-8200 2535);
PAINT MONO (-8200 2535);
DISPLAY INVISIBLE (-8200 2535);
WIRE 16 -1 (-8250 2525)(-8225 2525);
WIRE 16 -1 (-8250 2425)(-8250 2525);
WIRE 16 -1 (-8250 2425)(-8725 2425);
FORCEPROP 2 LAST SIG_NAME I3C_SPD_DDRGL_CPU0_SDA
J 0
(-8760 2435);
DISPLAY 0.489362 (-8760 2435);
WIRE 16 -1 (-7475 2575)(-8475 2575);
FORCEPROP 2 LAST SIG_NAME PD_CHL_CPU0_DIMM_SAA
J 0
(-8450 2585);
DISPLAY 0.489362 (-8450 2585);
DOT 1 (-2200 4175);
DOT 1 (-8500 3025);
DOT 1 (-2325 5800);
DOT 1 (-2900 5800);
DOT 1 (-2900 5375);
DOT 1 (-2200 5175);
DOT 1 (-400 5125);
DOT 1 (-400 5075);
DOT 1 (-400 5025);
DOT 1 (-400 4975);
DOT 1 (-400 4875);
DOT 1 (-400 4925);
DOT 1 (-400 4825);
DOT 1 (-400 4775);
DOT 1 (-400 4725);
DOT 1 (-400 4675);
DOT 1 (-400 4625);
DOT 1 (-400 4575);
DOT 1 (-400 4475);
DOT 1 (-400 4525);
DOT 1 (-400 4425);
DOT 1 (-400 4375);
DOT 1 (-400 4325);
DOT 1 (-400 4225);
DOT 1 (-400 4275);
DOT 1 (-400 4175);
DOT 1 (-400 4125);
DOT 1 (-400 4075);
DOT 1 (-400 3975);
DOT 1 (-400 4025);
DOT 1 (-400 3925);
DOT 1 (-400 3875);
DOT 1 (-400 3825);
DOT 1 (-400 3775);
DOT 1 (-400 3725);
DOT 1 (-400 3675);
DOT 1 (-400 3575);
DOT 1 (-400 3625);
DOT 1 (-2200 5125);
DOT 1 (-2200 4975);
DOT 1 (-2200 4875);
DOT 1 (-2200 4925);
DOT 1 (-2200 4825);
DOT 1 (-2200 4775);
DOT 1 (-2200 4675);
DOT 1 (-2200 4625);
DOT 1 (-2200 4575);
DOT 1 (-2200 4525);
DOT 1 (-2200 4475);
DOT 1 (-2200 4425);
DOT 1 (-2200 4375);
DOT 1 (-2200 4325);
DOT 1 (-2200 4225);
DOT 1 (-2200 4275);
DOT 1 (-2200 4125);
DOT 1 (-2200 4075);
DOT 1 (-2200 4025);
DOT 1 (-2200 3975);
DOT 1 (-2200 3925);
DOT 1 (-2200 3875);
DOT 1 (-2200 3825);
DOT 1 (-2200 3775);
DOT 1 (-2200 3725);
DOT 1 (-2200 3675);
DOT 1 (-2200 3625);
DOT 1 (-2200 3575);
DOT 1 (-400 3525);
DOT 1 (-400 3475);
DOT 1 (-400 3425);
DOT 1 (-400 3325);
DOT 1 (-400 3375);
DOT 1 (-400 3275);
DOT 1 (-400 3225);
DOT 1 (-400 3175);
DOT 1 (-400 3075);
DOT 1 (-400 3125);
DOT 1 (-400 3025);
DOT 1 (-400 2975);
DOT 1 (-400 2925);
DOT 1 (-400 2825);
DOT 1 (-400 2875);
DOT 1 (-400 2775);
DOT 1 (-400 2725);
DOT 1 (-400 2675);
DOT 1 (-400 2625);
DOT 1 (-400 2575);
DOT 1 (-400 2525);
DOT 1 (-400 2425);
DOT 1 (-400 2475);
DOT 1 (-400 2375);
DOT 1 (-400 2325);
DOT 1 (-400 2275);
DOT 1 (-400 2175);
DOT 1 (-400 2225);
DOT 1 (-400 2125);
DOT 1 (-400 2075);
DOT 1 (-400 2025);
DOT 1 (-400 1925);
DOT 1 (-400 1875);
DOT 1 (-400 1825);
DOT 1 (-2200 3525);
DOT 1 (-2200 3475);
DOT 1 (-2200 3425);
DOT 1 (-2200 3325);
DOT 1 (-2200 3375);
DOT 1 (-2200 3275);
DOT 1 (-2200 3225);
DOT 1 (-2200 3175);
DOT 1 (-2200 3075);
DOT 1 (-2200 3125);
DOT 1 (-2200 3025);
DOT 1 (-2200 2975);
DOT 1 (-2200 2925);
DOT 1 (-2200 2825);
DOT 1 (-2200 2875);
DOT 1 (-2200 2775);
DOT 1 (-2200 2725);
DOT 1 (-2200 2675);
DOT 1 (-2200 2625);
DOT 1 (-2200 2575);
DOT 1 (-2200 2525);
DOT 1 (-2200 2425);
DOT 1 (-2200 2475);
DOT 1 (-2200 2375);
DOT 1 (-2200 2325);
DOT 1 (-2200 2275);
DOT 1 (-2200 2175);
DOT 1 (-2200 2225);
DOT 1 (-2200 2125);
DOT 1 (-2200 2075);
DOT 1 (-2200 2025);
DOT 1 (-2200 1925);
DOT 1 (-2200 1975);
DOT 1 (-8350 1825);
DOT 1 (-2200 4725);
QUIT
